FILE_TYPE = MACRO_DRAWING;
SET COLOR_WIRE YELLOW;
SET COLOR_PROP ORANGE;
SET COLOR_DOT WHITE;
SET COLOR_ARC YELLOW;
SET COLOR_BODY GREEN;
SET COLOR_NOTE PURPLE;
SET PROP_DISPLAY VALUE;
SET PAGE_NUMBER P158;
FORCEADD GND..1
(-8750 5300);
FORCEPROP 3 LASTPIN (-8750 5350) SIG_NAME GND\g
J 0
(-8740 5360);
DISPLAY 0.659574 (-8740 5360);
PAINT MONO (-8740 5360);
DISPLAY INVISIBLE (-8740 5360);
FORCEPROP 1 LAST SIZE 1B
J 0
(-8675 5250);
DISPLAY 1.170213 (-8675 5250);
PAINT AQUA (-8675 5250);
DISPLAY INVISIBLE (-8675 5250);
FORCEPROP 2 LAST CDS_LIB pure_quanta_power
J 0
(-8750 5300);
DISPLAY INVISIBLE (-8750 5300);
FORCEPROP 1 LAST HDL_POWER GND
J 0
(-8750 5450);
DISPLAY 1.170213 (-8750 5450);
PAINT GREEN (-8750 5450);
DISPLAY INVISIBLE (-8750 5450);
FORCEPROP 1 LAST PATH I105
J 0
(-8675 5300);
DISPLAY 0.872340 (-8675 5300);
PAINT AQUA (-8675 5300);
DISPLAY INVISIBLE (-8675 5300);
FORCEADD GND..1
(-8675 5300);
FORCEPROP 3 LASTPIN (-8675 5350) SIG_NAME GND\g
J 0
(-8665 5360);
DISPLAY 0.659574 (-8665 5360);
PAINT MONO (-8665 5360);
DISPLAY INVISIBLE (-8665 5360);
FORCEPROP 2 LAST CDS_LIB pure_quanta_power
J 0
(-8675 5300);
DISPLAY INVISIBLE (-8675 5300);
FORCEPROP 1 LAST SIZE 1B
J 0
(-8600 5250);
DISPLAY 1.170213 (-8600 5250);
PAINT AQUA (-8600 5250);
DISPLAY INVISIBLE (-8600 5250);
FORCEPROP 1 LAST HDL_POWER GND
J 0
(-8675 5450);
DISPLAY 1.170213 (-8675 5450);
PAINT GREEN (-8675 5450);
DISPLAY INVISIBLE (-8675 5450);
FORCEPROP 1 LAST PATH I106
J 0
(-8600 5300);
DISPLAY 0.872340 (-8600 5300);
PAINT AQUA (-8600 5300);
DISPLAY INVISIBLE (-8600 5300);
FORCEADD GND..1
(-8575 4050);
FORCEPROP 3 LASTPIN (-8575 4100) SIG_NAME GND\g
J 0
(-8565 4110);
DISPLAY 0.659574 (-8565 4110);
PAINT MONO (-8565 4110);
DISPLAY INVISIBLE (-8565 4110);
FORCEPROP 1 LAST SIZE 1B
J 0
(-8500 4000);
DISPLAY 1.170213 (-8500 4000);
PAINT AQUA (-8500 4000);
DISPLAY INVISIBLE (-8500 4000);
FORCEPROP 2 LAST CDS_LIB pure_quanta_power
J 0
(-8575 4050);
DISPLAY INVISIBLE (-8575 4050);
FORCEPROP 1 LAST HDL_POWER GND
J 0
(-8575 4200);
DISPLAY 1.170213 (-8575 4200);
PAINT GREEN (-8575 4200);
DISPLAY INVISIBLE (-8575 4200);
FORCEPROP 1 LAST PATH I107
J 0
(-8500 4050);
DISPLAY 0.872340 (-8500 4050);
PAINT AQUA (-8500 4050);
DISPLAY INVISIBLE (-8500 4050);
FORCEADD OFFPAGE..3
R 2
(-8825 6000);
FORCEPROP 2 LAST $XR0 29 
J 0
(-9074 6000);
DISPLAY 0.638298 (-9074 6000);
PAINT MONO (-9074 6000);
FORCEPROP 2 LAST CDS_LIB standard
J 0
(-8825 6000);
DISPLAY INVISIBLE (-8825 6000);
FORCEPROP 1 LAST OFFPAGE TRUE
J 2
(-9150 5875);
DISPLAY 0.872340 (-9150 5875);
PAINT GREEN (-9150 5875);
DISPLAY INVISIBLE (-9150 5875);
FORCEPROP 1 LAST COMMENT_BODY TRUE
J 2
(-8775 5900);
DISPLAY 0.872340 (-8775 5900);
PAINT GREEN (-8775 5900);
DISPLAY INVISIBLE (-8775 5900);
FORCEPROP 2 LAST PATH I11
J 0
(-8775 6075);
DISPLAY 0.680851 (-8775 6075);
DISPLAY INVISIBLE (-8775 6075);
FORCEADD GND..1
(-8650 4050);
FORCEPROP 3 LASTPIN (-8650 4100) SIG_NAME GND\g
J 0
(-8640 4110);
DISPLAY 0.659574 (-8640 4110);
PAINT MONO (-8640 4110);
DISPLAY INVISIBLE (-8640 4110);
FORCEPROP 1 LAST SIZE 1B
J 0
(-8575 4000);
DISPLAY 1.170213 (-8575 4000);
PAINT AQUA (-8575 4000);
DISPLAY INVISIBLE (-8575 4000);
FORCEPROP 2 LAST CDS_LIB pure_quanta_power
J 0
(-8650 4050);
DISPLAY INVISIBLE (-8650 4050);
FORCEPROP 1 LAST HDL_POWER GND
J 0
(-8650 4200);
DISPLAY 1.170213 (-8650 4200);
PAINT GREEN (-8650 4200);
DISPLAY INVISIBLE (-8650 4200);
FORCEPROP 1 LAST PATH I110
J 0
(-8575 4050);
DISPLAY 0.872340 (-8575 4050);
PAINT AQUA (-8575 4050);
DISPLAY INVISIBLE (-8575 4050);
FORCEADD GND..1
(-6075 5050);
FORCEPROP 3 LASTPIN (-6075 5100) SIG_NAME GND\g
J 0
(-6065 5110);
DISPLAY 0.659574 (-6065 5110);
PAINT MONO (-6065 5110);
DISPLAY INVISIBLE (-6065 5110);
FORCEPROP 2 LAST CDS_LIB pure_quanta_power
J 0
(-6075 5050);
DISPLAY INVISIBLE (-6075 5050);
FORCEPROP 1 LAST SIZE 1B
J 0
(-6000 5000);
DISPLAY 1.170213 (-6000 5000);
PAINT AQUA (-6000 5000);
DISPLAY INVISIBLE (-6000 5000);
FORCEPROP 1 LAST HDL_POWER GND
J 0
(-6075 5200);
DISPLAY 1.170213 (-6075 5200);
PAINT GREEN (-6075 5200);
DISPLAY INVISIBLE (-6075 5200);
FORCEPROP 1 LAST PATH I113
J 0
(-6000 5050);
DISPLAY 0.872340 (-6000 5050);
PAINT AQUA (-6000 5050);
DISPLAY INVISIBLE (-6000 5050);
FORCEADD GND..1
(-6150 5050);
FORCEPROP 3 LASTPIN (-6150 5100) SIG_NAME GND\g
J 0
(-6140 5110);
DISPLAY 0.659574 (-6140 5110);
PAINT MONO (-6140 5110);
DISPLAY INVISIBLE (-6140 5110);
FORCEPROP 2 LAST CDS_LIB pure_quanta_power
J 0
(-6150 5050);
DISPLAY INVISIBLE (-6150 5050);
FORCEPROP 1 LAST SIZE 1B
J 0
(-6075 5000);
DISPLAY 1.170213 (-6075 5000);
PAINT AQUA (-6075 5000);
DISPLAY INVISIBLE (-6075 5000);
FORCEPROP 1 LAST HDL_POWER GND
J 0
(-6150 5200);
DISPLAY 1.170213 (-6150 5200);
PAINT GREEN (-6150 5200);
DISPLAY INVISIBLE (-6150 5200);
FORCEPROP 1 LAST PATH I114
J 0
(-6075 5050);
DISPLAY 0.872340 (-6075 5050);
PAINT AQUA (-6075 5050);
DISPLAY INVISIBLE (-6075 5050);
FORCEADD GND..1
(-6150 3700);
FORCEPROP 3 LASTPIN (-6150 3750) SIG_NAME GND\g
J 0
(-6140 3760);
DISPLAY 0.659574 (-6140 3760);
PAINT MONO (-6140 3760);
DISPLAY INVISIBLE (-6140 3760);
FORCEPROP 2 LAST CDS_LIB pure_quanta_power
J 0
(-6150 3700);
DISPLAY INVISIBLE (-6150 3700);
FORCEPROP 1 LAST SIZE 1B
J 0
(-6075 3650);
DISPLAY 1.170213 (-6075 3650);
PAINT AQUA (-6075 3650);
DISPLAY INVISIBLE (-6075 3650);
FORCEPROP 1 LAST HDL_POWER GND
J 0
(-6150 3850);
DISPLAY 1.170213 (-6150 3850);
PAINT GREEN (-6150 3850);
DISPLAY INVISIBLE (-6150 3850);
FORCEPROP 1 LAST PATH I117
J 0
(-6075 3700);
DISPLAY 0.872340 (-6075 3700);
PAINT AQUA (-6075 3700);
DISPLAY INVISIBLE (-6075 3700);
FORCEADD GND..1
(-6075 3700);
FORCEPROP 3 LASTPIN (-6075 3750) SIG_NAME GND\g
J 0
(-6065 3760);
DISPLAY 0.659574 (-6065 3760);
PAINT MONO (-6065 3760);
DISPLAY INVISIBLE (-6065 3760);
FORCEPROP 2 LAST CDS_LIB pure_quanta_power
J 0
(-6075 3700);
DISPLAY INVISIBLE (-6075 3700);
FORCEPROP 1 LAST SIZE 1B
J 0
(-6000 3650);
DISPLAY 1.170213 (-6000 3650);
PAINT AQUA (-6000 3650);
DISPLAY INVISIBLE (-6000 3650);
FORCEPROP 1 LAST HDL_POWER GND
J 0
(-6075 3850);
DISPLAY 1.170213 (-6075 3850);
PAINT GREEN (-6075 3850);
DISPLAY INVISIBLE (-6075 3850);
FORCEPROP 1 LAST PATH I118
J 0
(-6000 3700);
DISPLAY 0.872340 (-6000 3700);
PAINT AQUA (-6000 3700);
DISPLAY INVISIBLE (-6000 3700);
FORCEADD OFFPAGE..3
R 2
(-8825 5950);
FORCEPROP 2 LAST $XR0 29 
J 0
(-9074 5950);
DISPLAY 0.638298 (-9074 5950);
PAINT MONO (-9074 5950);
FORCEPROP 2 LAST CDS_LIB standard
J 0
(-8825 5950);
DISPLAY INVISIBLE (-8825 5950);
FORCEPROP 1 LAST OFFPAGE TRUE
J 2
(-9150 5825);
DISPLAY 0.872340 (-9150 5825);
PAINT GREEN (-9150 5825);
DISPLAY INVISIBLE (-9150 5825);
FORCEPROP 1 LAST COMMENT_BODY TRUE
J 2
(-8775 5850);
DISPLAY 0.872340 (-8775 5850);
PAINT GREEN (-8775 5850);
DISPLAY INVISIBLE (-8775 5850);
FORCEPROP 2 LAST PATH I12
J 0
(-8775 6025);
DISPLAY 0.680851 (-8775 6025);
DISPLAY INVISIBLE (-8775 6025);
FORCEADD Q_RES..2
R 2
(-8750 5650);
FORCEPROP 1 LAST LOCATION R339
J 2
(-8795 5775);
DISPLAY 0.808511 (-8795 5775);
FORCEPROP 0 LAST $SEC 1
J 0
(-8775 5825);
DISPLAY 0.680851 (-8775 5825);
PAINT MONO (-8775 5825);
DISPLAY INVISIBLE (-8775 5825);
FORCEPROP 0 LAST CDS_SEC 1
J 0
(-8775 5825);
DISPLAY 0.680851 (-8775 5825);
DISPLAY INVISIBLE (-8775 5825);
FORCEPROP 1 LASTPIN (-8750 5750) $PN 1
J 2
(-8755 5712);
DISPLAY 0.787234 (-8755 5712);
PAINT MONO (-8755 5712);
FORCEPROP 1 LASTPIN (-8750 5550) $PN 2
J 2
(-8755 5560);
DISPLAY 0.787234 (-8755 5560);
PAINT MONO (-8755 5560);
FORCEPROP 1 LAST VALUE 49.9
J 2
(-8795 5725);
DISPLAY 0.638298 (-8795 5725);
FORCEPROP 1 LAST TOLERANCE 1%
J 2
(-8795 5675);
DISPLAY 0.638298 (-8795 5675);
FORCEPROP 1 LAST MATERIAL EMPTY
J 2
(-8790 5575);
DISPLAY 0.638298 (-8790 5575);
FORCEPROP 1 LAST WATTAGE 1/20W
J 2
(-8790 5625);
DISPLAY 0.638298 (-8790 5625);
FORCEPROP 1 LAST PACK_TYPE 0201LF
J 2
(-8790 5475);
DISPLAY 0.638298 (-8790 5475);
FORCEPROP 2 LAST CDS_LIB pure_quanta
J 2
(-8750 5650);
DISPLAY INVISIBLE (-8750 5650);
FORCEPROP 1 LAST PATH I120
J 2
(-8800 5825);
DISPLAY 0.978723 (-8800 5825);
PAINT WHITE (-8800 5825);
DISPLAY INVISIBLE (-8800 5825);
FORCEPROP 1 LAST PART_NUMBER CS04991FE06
J 2
(-8790 5525);
DISPLAY 0.638298 (-8790 5525);
DISPLAY INVISIBLE (-8790 5525);
FORCEADD Q_RES..2
(-8675 5650);
FORCEPROP 1 LAST LOCATION R340
J 0
(-8630 5775);
DISPLAY 0.978723 (-8630 5775);
FORCEPROP 0 LAST $SEC 1
J 0
(-8625 5825);
DISPLAY 0.680851 (-8625 5825);
PAINT MONO (-8625 5825);
DISPLAY INVISIBLE (-8625 5825);
FORCEPROP 0 LAST CDS_SEC 1
J 0
(-8625 5825);
DISPLAY 0.680851 (-8625 5825);
DISPLAY INVISIBLE (-8625 5825);
FORCEPROP 1 LASTPIN (-8675 5750) $PN 1
J 0
(-8670 5712);
DISPLAY 0.787234 (-8670 5712);
PAINT MONO (-8670 5712);
FORCEPROP 1 LASTPIN (-8675 5550) $PN 2
J 0
(-8670 5560);
DISPLAY 0.787234 (-8670 5560);
PAINT MONO (-8670 5560);
FORCEPROP 1 LAST MATERIAL EMPTY
J 0
(-8635 5575);
DISPLAY 0.638298 (-8635 5575);
FORCEPROP 1 LAST TOLERANCE 1%
J 0
(-8630 5675);
DISPLAY 0.638298 (-8630 5675);
FORCEPROP 1 LAST PACK_TYPE 0201LF
J 0
(-8635 5475);
DISPLAY 0.638298 (-8635 5475);
FORCEPROP 1 LAST WATTAGE 1/20W
J 0
(-8635 5625);
DISPLAY 0.638298 (-8635 5625);
FORCEPROP 1 LAST VALUE 49.9
J 0
(-8630 5725);
DISPLAY 0.638298 (-8630 5725);
FORCEPROP 2 LAST CDS_LIB pure_quanta
J 2
(-8675 5650);
DISPLAY INVISIBLE (-8675 5650);
FORCEPROP 1 LAST PATH I121
J 0
(-8625 5825);
DISPLAY 0.978723 (-8625 5825);
PAINT WHITE (-8625 5825);
DISPLAY INVISIBLE (-8625 5825);
FORCEPROP 1 LAST PART_NUMBER CS04991FE06
J 0
(-8635 5525);
DISPLAY 0.638298 (-8635 5525);
DISPLAY INVISIBLE (-8635 5525);
FORCEADD Q_RES..2
(-6075 5400);
FORCEPROP 1 LAST LOCATION R345
J 0
(-6030 5525);
DISPLAY 0.978723 (-6030 5525);
FORCEPROP 0 LAST $SEC 1
J 0
(-6025 5575);
DISPLAY 0.680851 (-6025 5575);
PAINT MONO (-6025 5575);
DISPLAY INVISIBLE (-6025 5575);
FORCEPROP 0 LAST CDS_SEC 1
J 0
(-6025 5575);
DISPLAY 0.680851 (-6025 5575);
DISPLAY INVISIBLE (-6025 5575);
FORCEPROP 1 LASTPIN (-6075 5500) $PN 1
J 0
(-6070 5462);
DISPLAY 0.787234 (-6070 5462);
PAINT MONO (-6070 5462);
FORCEPROP 1 LASTPIN (-6075 5300) $PN 2
J 0
(-6070 5310);
DISPLAY 0.787234 (-6070 5310);
PAINT MONO (-6070 5310);
FORCEPROP 1 LAST VALUE 49.9
J 0
(-6030 5475);
DISPLAY 0.638298 (-6030 5475);
FORCEPROP 1 LAST PACK_TYPE 0201LF
J 0
(-6035 5225);
DISPLAY 0.638298 (-6035 5225);
FORCEPROP 1 LAST MATERIAL EMPTY
J 0
(-6035 5325);
DISPLAY 0.638298 (-6035 5325);
FORCEPROP 1 LAST WATTAGE 1/20W
J 0
(-6035 5375);
DISPLAY 0.638298 (-6035 5375);
FORCEPROP 1 LAST TOLERANCE 1%
J 0
(-6030 5425);
DISPLAY 0.638298 (-6030 5425);
FORCEPROP 2 LAST CDS_LIB pure_quanta
J 0
(-6075 5400);
DISPLAY INVISIBLE (-6075 5400);
FORCEPROP 1 LAST PATH I124
J 0
(-6025 5575);
DISPLAY 0.978723 (-6025 5575);
PAINT WHITE (-6025 5575);
DISPLAY INVISIBLE (-6025 5575);
FORCEPROP 1 LAST PART_NUMBER CS04991FE06
J 0
(-6035 5275);
DISPLAY 0.638298 (-6035 5275);
DISPLAY INVISIBLE (-6035 5275);
FORCEADD Q_RES..2
R 2
(-6150 5400);
FORCEPROP 1 LAST LOCATION R343
J 2
(-6195 5525);
DISPLAY 0.978723 (-6195 5525);
FORCEPROP 0 LAST $SEC 1
J 0
(-6175 5575);
DISPLAY 0.680851 (-6175 5575);
PAINT MONO (-6175 5575);
DISPLAY INVISIBLE (-6175 5575);
FORCEPROP 0 LAST CDS_SEC 1
J 0
(-6175 5575);
DISPLAY 0.680851 (-6175 5575);
DISPLAY INVISIBLE (-6175 5575);
FORCEPROP 1 LASTPIN (-6150 5500) $PN 1
J 2
(-6155 5462);
DISPLAY 0.787234 (-6155 5462);
PAINT MONO (-6155 5462);
FORCEPROP 1 LASTPIN (-6150 5300) $PN 2
J 2
(-6155 5310);
DISPLAY 0.787234 (-6155 5310);
PAINT MONO (-6155 5310);
FORCEPROP 1 LAST TOLERANCE 1%
J 2
(-6195 5425);
DISPLAY 0.638298 (-6195 5425);
FORCEPROP 1 LAST MATERIAL EMPTY
J 2
(-6190 5325);
DISPLAY 0.638298 (-6190 5325);
FORCEPROP 1 LAST WATTAGE 1/20W
J 2
(-6190 5375);
DISPLAY 0.638298 (-6190 5375);
FORCEPROP 1 LAST PACK_TYPE 0201LF
J 2
(-6190 5225);
DISPLAY 0.638298 (-6190 5225);
FORCEPROP 1 LAST VALUE 49.9
J 2
(-6195 5475);
DISPLAY 0.638298 (-6195 5475);
FORCEPROP 2 LAST CDS_LIB pure_quanta
J 0
(-6150 5400);
DISPLAY INVISIBLE (-6150 5400);
FORCEPROP 1 LAST PATH I125
J 2
(-6200 5575);
DISPLAY 0.978723 (-6200 5575);
PAINT WHITE (-6200 5575);
DISPLAY INVISIBLE (-6200 5575);
FORCEPROP 1 LAST PART_NUMBER CS04991FE06
J 2
(-6190 5275);
DISPLAY 0.638298 (-6190 5275);
DISPLAY INVISIBLE (-6190 5275);
FORCEADD Q_RES..2
(-6075 4050);
FORCEPROP 1 LAST LOCATION R346
J 0
(-6030 4175);
DISPLAY 0.978723 (-6030 4175);
FORCEPROP 0 LAST $SEC 1
J 0
(-6025 4225);
DISPLAY 0.680851 (-6025 4225);
PAINT MONO (-6025 4225);
DISPLAY INVISIBLE (-6025 4225);
FORCEPROP 0 LAST CDS_SEC 1
J 0
(-6025 4225);
DISPLAY 0.680851 (-6025 4225);
DISPLAY INVISIBLE (-6025 4225);
FORCEPROP 1 LASTPIN (-6075 4150) $PN 1
J 0
(-6070 4112);
DISPLAY 0.787234 (-6070 4112);
PAINT MONO (-6070 4112);
FORCEPROP 1 LASTPIN (-6075 3950) $PN 2
J 0
(-6070 3960);
DISPLAY 0.787234 (-6070 3960);
PAINT MONO (-6070 3960);
FORCEPROP 1 LAST TOLERANCE 1%
J 0
(-6030 4075);
DISPLAY 0.638298 (-6030 4075);
FORCEPROP 1 LAST PACK_TYPE 0201LF
J 0
(-6035 3875);
DISPLAY 0.638298 (-6035 3875);
FORCEPROP 1 LAST VALUE 49.9
J 0
(-6030 4125);
DISPLAY 0.638298 (-6030 4125);
FORCEPROP 1 LAST MATERIAL EMPTY
J 0
(-6035 3975);
DISPLAY 0.638298 (-6035 3975);
FORCEPROP 1 LAST WATTAGE 1/20W
J 0
(-6035 4025);
DISPLAY 0.638298 (-6035 4025);
FORCEPROP 2 LAST CDS_LIB pure_quanta
J 0
(-6075 4050);
DISPLAY INVISIBLE (-6075 4050);
FORCEPROP 1 LAST PATH I126
J 0
(-6025 4225);
DISPLAY 0.978723 (-6025 4225);
PAINT WHITE (-6025 4225);
DISPLAY INVISIBLE (-6025 4225);
FORCEPROP 1 LAST PART_NUMBER CS04991FE06
J 0
(-6035 3925);
DISPLAY 0.638298 (-6035 3925);
DISPLAY INVISIBLE (-6035 3925);
FORCEADD Q_RES..2
R 2
(-6150 4050);
FORCEPROP 1 LAST LOCATION R344
J 2
(-6195 4175);
DISPLAY 0.978723 (-6195 4175);
FORCEPROP 0 LAST $SEC 1
J 0
(-6175 4225);
DISPLAY 0.680851 (-6175 4225);
PAINT MONO (-6175 4225);
DISPLAY INVISIBLE (-6175 4225);
FORCEPROP 0 LAST CDS_SEC 1
J 0
(-6175 4225);
DISPLAY 0.680851 (-6175 4225);
DISPLAY INVISIBLE (-6175 4225);
FORCEPROP 1 LASTPIN (-6150 4150) $PN 1
J 2
(-6155 4112);
DISPLAY 0.787234 (-6155 4112);
PAINT MONO (-6155 4112);
FORCEPROP 1 LASTPIN (-6150 3950) $PN 2
J 2
(-6155 3960);
DISPLAY 0.787234 (-6155 3960);
PAINT MONO (-6155 3960);
FORCEPROP 1 LAST VALUE 49.9
J 2
(-6195 4125);
DISPLAY 0.638298 (-6195 4125);
FORCEPROP 1 LAST PACK_TYPE 0201LF
J 2
(-6190 3875);
DISPLAY 0.638298 (-6190 3875);
FORCEPROP 1 LAST MATERIAL EMPTY
J 2
(-6190 3975);
DISPLAY 0.638298 (-6190 3975);
FORCEPROP 1 LAST WATTAGE 1/20W
J 2
(-6190 4025);
DISPLAY 0.638298 (-6190 4025);
FORCEPROP 1 LAST TOLERANCE 1%
J 2
(-6195 4075);
DISPLAY 0.638298 (-6195 4075);
FORCEPROP 2 LAST CDS_LIB pure_quanta
J 0
(-6150 4050);
DISPLAY INVISIBLE (-6150 4050);
FORCEPROP 1 LAST PATH I127
J 2
(-6200 4225);
DISPLAY 0.978723 (-6200 4225);
PAINT WHITE (-6200 4225);
DISPLAY INVISIBLE (-6200 4225);
FORCEPROP 1 LAST PART_NUMBER CS04991FE06
J 2
(-6190 3925);
DISPLAY 0.638298 (-6190 3925);
DISPLAY INVISIBLE (-6190 3925);
FORCEADD OFFPAGE..3
(-5900 6000);
FORCEPROP 2 LAST $XR0 176 
J 0
(-5686 6000);
DISPLAY 0.638298 (-5686 6000);
PAINT MONO (-5686 6000);
FORCEPROP 2 LAST CDS_LIB standard
J 2
(-5900 6000);
DISPLAY INVISIBLE (-5900 6000);
FORCEPROP 1 LAST OFFPAGE TRUE
J 0
(-5575 5875);
DISPLAY 0.872340 (-5575 5875);
PAINT GREEN (-5575 5875);
DISPLAY INVISIBLE (-5575 5875);
FORCEPROP 1 LAST COMMENT_BODY TRUE
J 0
(-5950 5900);
DISPLAY 0.872340 (-5950 5900);
PAINT GREEN (-5950 5900);
DISPLAY INVISIBLE (-5950 5900);
FORCEPROP 2 LAST PATH I13
J 2
(-5950 6075);
DISPLAY 0.680851 (-5950 6075);
DISPLAY INVISIBLE (-5950 6075);
FORCEADD Q_CAP..2
(-3150 4550);
FORCEPROP 1 LAST LOCATION C6023
J 1
(-3325 4550);
DISPLAY 0.638298 (-3325 4550);
FORCEPROP 0 LAST $SEC 1
J 0
(-3325 4600);
DISPLAY 0.680851 (-3325 4600);
PAINT MONO (-3325 4600);
DISPLAY INVISIBLE (-3325 4600);
FORCEPROP 0 LAST CDS_SEC 1
J 0
(-3325 4600);
DISPLAY 0.680851 (-3325 4600);
DISPLAY INVISIBLE (-3325 4600);
FORCEPROP 1 LASTPIN (-3250 4550) $PN 1
J 0
(-3260 4565);
DISPLAY 0.787234 (-3260 4565);
PAINT MONO (-3260 4565);
FORCEPROP 1 LASTPIN (-3050 4550) $PN 2
J 0
(-3065 4565);
DISPLAY 0.787234 (-3065 4565);
PAINT MONO (-3065 4565);
FORCEPROP 0 LAST ROOM USB3_HUB1
J 0
(-3275 4625);
DISPLAY 0.553191 (-3275 4625);
FORCEPROP 2 LAST CDS_LIB pure_quanta
J 0
(-3150 4550);
DISPLAY INVISIBLE (-3150 4550);
FORCEPROP 1 LAST VOLTAGE 25V
J 0
(-3125 4350);
DISPLAY 0.638298 (-3125 4350);
DISPLAY INVISIBLE (-3125 4350);
FORCEPROP 1 LAST VALUE 0.1UF
J 2
(-3125 4350);
DISPLAY 0.638298 (-3125 4350);
DISPLAY INVISIBLE (-3125 4350);
FORCEPROP 1 LAST TOLERANCE 10%
J 2
(-3125 4300);
DISPLAY 0.638298 (-3125 4300);
DISPLAY INVISIBLE (-3125 4300);
FORCEPROP 1 LAST PACK_TYPE 0402
J 1
(-3125 4250);
DISPLAY 0.638298 (-3125 4250);
DISPLAY INVISIBLE (-3125 4250);
FORCEPROP 1 LAST MATERIAL X7R
J 0
(-3125 4300);
DISPLAY 0.638298 (-3125 4300);
DISPLAY INVISIBLE (-3125 4300);
FORCEPROP 1 LAST PATH I137
J 0
(-3150 4750);
DISPLAY 0.978723 (-3150 4750);
PAINT WHITE (-3150 4750);
DISPLAY INVISIBLE (-3150 4750);
FORCEPROP 1 LAST PART_NUMBER CH4104K1B00
J 1
(-3125 4225);
DISPLAY 0.510638 (-3125 4225);
DISPLAY INVISIBLE (-3125 4225);
FORCEADD Q_CAP..2
(-3150 4500);
FORCEPROP 1 LAST LOCATION C6024
J 1
(-3325 4500);
DISPLAY 0.638298 (-3325 4500);
FORCEPROP 0 LAST $SEC 1
J 0
(-3150 4775);
DISPLAY 0.680851 (-3150 4775);
PAINT MONO (-3150 4775);
DISPLAY INVISIBLE (-3150 4775);
FORCEPROP 0 LAST CDS_SEC 1
J 0
(-3150 4775);
DISPLAY 0.680851 (-3150 4775);
DISPLAY INVISIBLE (-3150 4775);
FORCEPROP 1 LASTPIN (-3250 4500) $PN 1
J 0
(-3260 4515);
DISPLAY 0.787234 (-3260 4515);
PAINT MONO (-3260 4515);
FORCEPROP 1 LASTPIN (-3050 4500) $PN 2
J 0
(-3065 4515);
DISPLAY 0.787234 (-3065 4515);
PAINT MONO (-3065 4515);
FORCEPROP 1 LAST VALUE 0.1UF
J 2
(-3125 4725);
DISPLAY 0.638298 (-3125 4725);
FORCEPROP 1 LAST VOLTAGE 25V
J 0
(-3125 4725);
DISPLAY 0.638298 (-3125 4725);
FORCEPROP 1 LAST MATERIAL X7R
J 0
(-3025 4725);
DISPLAY 0.638298 (-3025 4725);
FORCEPROP 1 LAST PACK_TYPE 0402
J 1
(-3200 4675);
DISPLAY 0.638298 (-3200 4675);
FORCEPROP 0 LAST ROOM USB3_HUB1
J 0
(-3275 4400);
DISPLAY 0.680851 (-3275 4400);
FORCEPROP 1 LAST TOLERANCE 10%
J 2
(-3025 4675);
DISPLAY 0.638298 (-3025 4675);
FORCEPROP 2 LAST CDS_LIB pure_quanta
J 0
(-3150 4500);
DISPLAY INVISIBLE (-3150 4500);
FORCEPROP 1 LAST PATH I138
J 0
(-3150 4700);
DISPLAY 0.978723 (-3150 4700);
PAINT WHITE (-3150 4700);
DISPLAY INVISIBLE (-3150 4700);
FORCEPROP 1 LAST PART_NUMBER CH4104K1B00
J 1
(-3150 4775);
DISPLAY 0.510638 (-3150 4775);
DISPLAY INVISIBLE (-3150 4775);
FORCEADD Q_CAP..2
(-3125 3975);
FORCEPROP 1 LAST LOCATION C6025
J 1
(-3275 3975);
DISPLAY 0.638298 (-3275 3975);
FORCEPROP 0 LAST $SEC 1
J 0
(-3275 4025);
DISPLAY 0.680851 (-3275 4025);
PAINT MONO (-3275 4025);
DISPLAY INVISIBLE (-3275 4025);
FORCEPROP 0 LAST CDS_SEC 1
J 0
(-3275 4025);
DISPLAY 0.680851 (-3275 4025);
DISPLAY INVISIBLE (-3275 4025);
FORCEPROP 1 LASTPIN (-3225 3975) $PN 1
J 0
(-3235 3990);
DISPLAY 0.787234 (-3235 3990);
PAINT MONO (-3235 3990);
FORCEPROP 1 LASTPIN (-3025 3975) $PN 2
J 0
(-3040 3990);
DISPLAY 0.787234 (-3040 3990);
PAINT MONO (-3040 3990);
FORCEPROP 0 LAST ROOM USB3_HUB2
J 0
(-3250 4025);
DISPLAY 0.680851 (-3250 4025);
FORCEPROP 2 LAST CDS_LIB pure_quanta
J 0
(-3125 3975);
DISPLAY INVISIBLE (-3125 3975);
FORCEPROP 1 LAST VOLTAGE 25V
J 0
(-3100 3775);
DISPLAY 0.638298 (-3100 3775);
DISPLAY INVISIBLE (-3100 3775);
FORCEPROP 1 LAST VALUE 0.1UF
J 2
(-3100 3775);
DISPLAY 0.638298 (-3100 3775);
DISPLAY INVISIBLE (-3100 3775);
FORCEPROP 1 LAST TOLERANCE 10%
J 2
(-3100 3725);
DISPLAY 0.638298 (-3100 3725);
DISPLAY INVISIBLE (-3100 3725);
FORCEPROP 1 LAST PACK_TYPE 0402
J 1
(-3100 3675);
DISPLAY 0.638298 (-3100 3675);
DISPLAY INVISIBLE (-3100 3675);
FORCEPROP 1 LAST MATERIAL X7R
J 0
(-3100 3725);
DISPLAY 0.638298 (-3100 3725);
DISPLAY INVISIBLE (-3100 3725);
FORCEPROP 1 LAST PATH I139
J 0
(-3125 4175);
DISPLAY 0.978723 (-3125 4175);
PAINT WHITE (-3125 4175);
DISPLAY INVISIBLE (-3125 4175);
FORCEPROP 1 LAST PART_NUMBER CH4104K1B00
J 1
(-3100 3650);
DISPLAY 0.510638 (-3100 3650);
DISPLAY INVISIBLE (-3100 3650);
FORCEADD OFFPAGE..3
(-5900 5950);
FORCEPROP 2 LAST $XR0 176 
J 0
(-5686 5950);
DISPLAY 0.638298 (-5686 5950);
PAINT MONO (-5686 5950);
FORCEPROP 2 LAST CDS_LIB standard
J 0
(-5900 5950);
DISPLAY INVISIBLE (-5900 5950);
FORCEPROP 1 LAST OFFPAGE TRUE
J 0
(-5575 5825);
DISPLAY 0.872340 (-5575 5825);
PAINT GREEN (-5575 5825);
DISPLAY INVISIBLE (-5575 5825);
FORCEPROP 1 LAST COMMENT_BODY TRUE
J 0
(-5950 5850);
DISPLAY 0.872340 (-5950 5850);
PAINT GREEN (-5950 5850);
DISPLAY INVISIBLE (-5950 5850);
FORCEPROP 2 LAST PATH I14
J 0
(-5700 6025);
DISPLAY 0.680851 (-5700 6025);
DISPLAY INVISIBLE (-5700 6025);
FORCEADD Q_CAP..2
(-3125 3925);
FORCEPROP 1 LAST LOCATION C6026
J 1
(-3275 3925);
DISPLAY 0.638298 (-3275 3925);
FORCEPROP 0 LAST $SEC 1
J 0
(-3100 4100);
DISPLAY 0.680851 (-3100 4100);
PAINT MONO (-3100 4100);
DISPLAY INVISIBLE (-3100 4100);
FORCEPROP 0 LAST CDS_SEC 1
J 0
(-3100 4100);
DISPLAY 0.680851 (-3100 4100);
DISPLAY INVISIBLE (-3100 4100);
FORCEPROP 1 LASTPIN (-3225 3925) $PN 1
J 0
(-3235 3940);
DISPLAY 0.787234 (-3235 3940);
PAINT MONO (-3235 3940);
FORCEPROP 1 LASTPIN (-3025 3925) $PN 2
J 0
(-3040 3940);
DISPLAY 0.787234 (-3040 3940);
PAINT MONO (-3040 3940);
FORCEPROP 1 LAST VALUE 0.1UF
J 2
(-3100 4100);
DISPLAY 0.638298 (-3100 4100);
FORCEPROP 1 LAST VOLTAGE 25V
J 0
(-3100 4100);
DISPLAY 0.638298 (-3100 4100);
FORCEPROP 0 LAST ROOM USB3_HUB2
J 0
(-3275 3850);
DISPLAY 0.680851 (-3275 3850);
FORCEPROP 2 LAST CDS_LIB pure_quanta
J 0
(-3125 3925);
DISPLAY INVISIBLE (-3125 3925);
FORCEPROP 1 LAST TOLERANCE 10%
J 2
(-3000 4075);
DISPLAY 0.638298 (-3000 4075);
DISPLAY INVISIBLE (-3000 4075);
FORCEPROP 1 LAST PACK_TYPE 0402
J 1
(-3175 4075);
DISPLAY 0.638298 (-3175 4075);
DISPLAY INVISIBLE (-3175 4075);
FORCEPROP 1 LAST MATERIAL X7R
J 0
(-3000 4125);
DISPLAY 0.638298 (-3000 4125);
DISPLAY INVISIBLE (-3000 4125);
FORCEPROP 1 LAST PATH I140
J 0
(-3125 4125);
DISPLAY 0.978723 (-3125 4125);
PAINT WHITE (-3125 4125);
DISPLAY INVISIBLE (-3125 4125);
FORCEPROP 1 LAST PART_NUMBER CH4104K1B00
J 1
(-3125 4175);
DISPLAY 0.510638 (-3125 4175);
DISPLAY INVISIBLE (-3125 4175);
FORCEADD Q_CAP..2
(-7575 4400);
FORCEPROP 1 LAST LOCATION C6014
J 1
(-7750 4400);
DISPLAY 0.638298 (-7750 4400);
FORCEPROP 0 LAST $SEC 1
J 0
(-7550 4575);
DISPLAY 0.680851 (-7550 4575);
PAINT MONO (-7550 4575);
DISPLAY INVISIBLE (-7550 4575);
FORCEPROP 0 LAST CDS_SEC 1
J 0
(-7550 4575);
DISPLAY 0.680851 (-7550 4575);
DISPLAY INVISIBLE (-7550 4575);
FORCEPROP 1 LASTPIN (-7675 4400) $PN 1
J 0
(-7685 4415);
DISPLAY 0.787234 (-7685 4415);
PAINT MONO (-7685 4415);
FORCEPROP 1 LASTPIN (-7475 4400) $PN 2
J 0
(-7490 4415);
DISPLAY 0.787234 (-7490 4415);
PAINT MONO (-7490 4415);
FORCEPROP 1 LAST VALUE 0.1UF
J 2
(-7550 4575);
DISPLAY 0.638298 (-7550 4575);
FORCEPROP 1 LAST VOLTAGE 25V
J 0
(-7550 4575);
DISPLAY 0.638298 (-7550 4575);
FORCEPROP 0 LAST ROOM USB3_HUB2
J 0
(-7700 4300);
DISPLAY 0.680851 (-7700 4300);
FORCEPROP 1 LAST TOLERANCE 10%
J 2
(-7450 4550);
DISPLAY 0.638298 (-7450 4550);
DISPLAY INVISIBLE (-7450 4550);
FORCEPROP 1 LAST PACK_TYPE 0402
J 1
(-7625 4550);
DISPLAY 0.638298 (-7625 4550);
DISPLAY INVISIBLE (-7625 4550);
FORCEPROP 1 LAST MATERIAL X7R
J 0
(-7450 4600);
DISPLAY 0.638298 (-7450 4600);
DISPLAY INVISIBLE (-7450 4600);
FORCEPROP 2 LAST CDS_LIB pure_quanta
J 0
(-7575 4400);
DISPLAY INVISIBLE (-7575 4400);
FORCEPROP 1 LAST PATH I141
J 0
(-7575 4600);
DISPLAY 0.978723 (-7575 4600);
PAINT WHITE (-7575 4600);
DISPLAY INVISIBLE (-7575 4600);
FORCEPROP 1 LAST PART_NUMBER CH4104K1B00
J 1
(-7575 4650);
DISPLAY 0.510638 (-7575 4650);
DISPLAY INVISIBLE (-7575 4650);
FORCEADD Q_CAP..2
(-7575 4450);
FORCEPROP 1 LAST LOCATION C6013
J 1
(-7750 4450);
DISPLAY 0.638298 (-7750 4450);
FORCEPROP 0 LAST $SEC 1
J 0
(-7725 4500);
DISPLAY 0.680851 (-7725 4500);
PAINT MONO (-7725 4500);
DISPLAY INVISIBLE (-7725 4500);
FORCEPROP 0 LAST CDS_SEC 1
J 0
(-7725 4500);
DISPLAY 0.680851 (-7725 4500);
DISPLAY INVISIBLE (-7725 4500);
FORCEPROP 1 LASTPIN (-7675 4450) $PN 1
J 0
(-7685 4465);
DISPLAY 0.787234 (-7685 4465);
PAINT MONO (-7685 4465);
FORCEPROP 1 LASTPIN (-7475 4450) $PN 2
J 0
(-7490 4465);
DISPLAY 0.787234 (-7490 4465);
PAINT MONO (-7490 4465);
FORCEPROP 0 LAST ROOM USB3_HUB2
J 0
(-7725 4525);
DISPLAY 0.680851 (-7725 4525);
FORCEPROP 1 LAST VOLTAGE 25V
J 0
(-7550 4250);
DISPLAY 0.638298 (-7550 4250);
DISPLAY INVISIBLE (-7550 4250);
FORCEPROP 1 LAST VALUE 0.1UF
J 2
(-7550 4250);
DISPLAY 0.638298 (-7550 4250);
DISPLAY INVISIBLE (-7550 4250);
FORCEPROP 1 LAST TOLERANCE 10%
J 2
(-7550 4200);
DISPLAY 0.638298 (-7550 4200);
DISPLAY INVISIBLE (-7550 4200);
FORCEPROP 1 LAST PACK_TYPE 0402
J 1
(-7550 4150);
DISPLAY 0.638298 (-7550 4150);
DISPLAY INVISIBLE (-7550 4150);
FORCEPROP 1 LAST MATERIAL X7R
J 0
(-7550 4200);
DISPLAY 0.638298 (-7550 4200);
DISPLAY INVISIBLE (-7550 4200);
FORCEPROP 2 LAST CDS_LIB pure_quanta
J 0
(-7575 4450);
DISPLAY INVISIBLE (-7575 4450);
FORCEPROP 1 LAST PATH I142
J 0
(-7575 4650);
DISPLAY 0.978723 (-7575 4650);
PAINT WHITE (-7575 4650);
DISPLAY INVISIBLE (-7575 4650);
FORCEPROP 1 LAST PART_NUMBER CH4104K1B00
J 1
(-7550 4125);
DISPLAY 0.510638 (-7550 4125);
DISPLAY INVISIBLE (-7550 4125);
FORCEADD Q_CAP..2
(-7575 4750);
FORCEPROP 1 LAST LOCATION C6004
J 1
(-7750 4750);
DISPLAY 0.638298 (-7750 4750);
FORCEPROP 0 LAST $SEC 1
J 0
(-7575 5025);
DISPLAY 0.680851 (-7575 5025);
PAINT MONO (-7575 5025);
DISPLAY INVISIBLE (-7575 5025);
FORCEPROP 0 LAST CDS_SEC 1
J 0
(-7575 5025);
DISPLAY 0.680851 (-7575 5025);
DISPLAY INVISIBLE (-7575 5025);
FORCEPROP 1 LASTPIN (-7675 4750) $PN 1
J 0
(-7685 4765);
DISPLAY 0.787234 (-7685 4765);
PAINT MONO (-7685 4765);
FORCEPROP 1 LASTPIN (-7475 4750) $PN 2
J 0
(-7490 4765);
DISPLAY 0.787234 (-7490 4765);
PAINT MONO (-7490 4765);
FORCEPROP 0 LAST ROOM USB3_HUB1
J 0
(-7700 4675);
DISPLAY 0.680851 (-7700 4675);
FORCEPROP 1 LAST TOLERANCE 10%
J 2
(-7450 4975);
DISPLAY 0.638298 (-7450 4975);
FORCEPROP 1 LAST MATERIAL X7R
J 0
(-7450 5025);
DISPLAY 0.638298 (-7450 5025);
FORCEPROP 1 LAST VOLTAGE 25V
J 0
(-7550 5025);
DISPLAY 0.638298 (-7550 5025);
FORCEPROP 1 LAST VALUE 0.1UF
J 2
(-7550 5025);
DISPLAY 0.638298 (-7550 5025);
FORCEPROP 1 LAST PACK_TYPE 0402
J 1
(-7625 4975);
DISPLAY 0.638298 (-7625 4975);
FORCEPROP 2 LAST CDS_LIB pure_quanta
J 0
(-7575 4750);
DISPLAY INVISIBLE (-7575 4750);
FORCEPROP 1 LAST PATH I143
J 0
(-7575 4950);
DISPLAY 0.978723 (-7575 4950);
PAINT WHITE (-7575 4950);
DISPLAY INVISIBLE (-7575 4950);
FORCEPROP 1 LAST PART_NUMBER CH4104K1B00
J 1
(-7575 5075);
DISPLAY 0.510638 (-7575 5075);
DISPLAY INVISIBLE (-7575 5075);
FORCEADD Q_CAP..2
(-7575 4800);
FORCEPROP 1 LAST LOCATION C6003
J 1
(-7750 4800);
DISPLAY 0.638298 (-7750 4800);
FORCEPROP 0 LAST $SEC 1
J 0
(-7750 4850);
DISPLAY 0.680851 (-7750 4850);
PAINT MONO (-7750 4850);
DISPLAY INVISIBLE (-7750 4850);
FORCEPROP 0 LAST CDS_SEC 1
J 0
(-7750 4850);
DISPLAY 0.680851 (-7750 4850);
DISPLAY INVISIBLE (-7750 4850);
FORCEPROP 1 LASTPIN (-7675 4800) $PN 1
J 0
(-7685 4815);
DISPLAY 0.787234 (-7685 4815);
PAINT MONO (-7685 4815);
FORCEPROP 1 LASTPIN (-7475 4800) $PN 2
J 0
(-7490 4815);
DISPLAY 0.787234 (-7490 4815);
PAINT MONO (-7490 4815);
FORCEPROP 0 LAST ROOM USB3_HUB1
J 0
(-7700 4900);
DISPLAY 0.680851 (-7700 4900);
FORCEPROP 1 LAST VOLTAGE 25V
J 0
(-7550 4600);
DISPLAY 0.638298 (-7550 4600);
DISPLAY INVISIBLE (-7550 4600);
FORCEPROP 1 LAST VALUE 0.1UF
J 2
(-7550 4600);
DISPLAY 0.638298 (-7550 4600);
DISPLAY INVISIBLE (-7550 4600);
FORCEPROP 1 LAST TOLERANCE 10%
J 2
(-7550 4550);
DISPLAY 0.638298 (-7550 4550);
DISPLAY INVISIBLE (-7550 4550);
FORCEPROP 1 LAST PACK_TYPE 0402
J 1
(-7550 4500);
DISPLAY 0.638298 (-7550 4500);
DISPLAY INVISIBLE (-7550 4500);
FORCEPROP 1 LAST MATERIAL X7R
J 0
(-7550 4550);
DISPLAY 0.638298 (-7550 4550);
DISPLAY INVISIBLE (-7550 4550);
FORCEPROP 2 LAST CDS_LIB pure_quanta
J 0
(-7575 4800);
DISPLAY INVISIBLE (-7575 4800);
FORCEPROP 1 LAST PATH I144
J 0
(-7575 5000);
DISPLAY 0.978723 (-7575 5000);
PAINT WHITE (-7575 5000);
DISPLAY INVISIBLE (-7575 5000);
FORCEPROP 1 LAST PART_NUMBER CH4104K1B00
J 1
(-7550 4475);
DISPLAY 0.510638 (-7550 4475);
DISPLAY INVISIBLE (-7550 4475);
FORCEADD Q_RES..2
R 2
(-8650 4400);
FORCEPROP 1 LAST LOCATION R341
J 2
(-8695 4525);
DISPLAY 0.787234 (-8695 4525);
FORCEPROP 0 LAST $SEC 1
J 0
(-8675 4575);
DISPLAY 0.680851 (-8675 4575);
PAINT MONO (-8675 4575);
DISPLAY INVISIBLE (-8675 4575);
FORCEPROP 0 LAST CDS_SEC 1
J 0
(-8675 4575);
DISPLAY 0.680851 (-8675 4575);
DISPLAY INVISIBLE (-8675 4575);
FORCEPROP 1 LASTPIN (-8650 4500) $PN 1
J 2
(-8655 4462);
DISPLAY 0.787234 (-8655 4462);
PAINT MONO (-8655 4462);
FORCEPROP 1 LASTPIN (-8650 4300) $PN 2
J 2
(-8655 4310);
DISPLAY 0.787234 (-8655 4310);
PAINT MONO (-8655 4310);
FORCEPROP 1 LAST VALUE 51
J 2
(-8695 4475);
DISPLAY 0.787234 (-8695 4475);
FORCEPROP 1 LAST TOLERANCE 5%
J 2
(-8695 4425);
DISPLAY 0.787234 (-8695 4425);
FORCEPROP 1 LAST MATERIAL EMPTY
J 2
(-8690 4325);
DISPLAY 0.787234 (-8690 4325);
FORCEPROP 1 LAST WATTAGE 1/16W
J 2
(-8690 4375);
DISPLAY 0.787234 (-8690 4375);
FORCEPROP 1 LAST PACK_TYPE 0402LF
J 2
(-8690 4225);
DISPLAY 0.787234 (-8690 4225);
FORCEPROP 2 LAST CDS_LIB pure_quanta
J 2
(-8650 4400);
DISPLAY INVISIBLE (-8650 4400);
FORCEPROP 1 LAST PATH I145
J 2
(-8700 4575);
DISPLAY 0.978723 (-8700 4575);
PAINT WHITE (-8700 4575);
DISPLAY INVISIBLE (-8700 4575);
FORCEPROP 1 LAST PART_NUMBER CS05102JB04
J 2
(-8690 4275);
DISPLAY 0.787234 (-8690 4275);
DISPLAY INVISIBLE (-8690 4275);
FORCEADD Q_RES..2
(-8575 4425);
FORCEPROP 1 LAST LOCATION R342
J 0
(-8530 4550);
DISPLAY 0.978723 (-8530 4550);
FORCEPROP 0 LAST $SEC 1
J 0
(-8525 4600);
DISPLAY 0.680851 (-8525 4600);
PAINT MONO (-8525 4600);
DISPLAY INVISIBLE (-8525 4600);
FORCEPROP 0 LAST CDS_SEC 1
J 0
(-8525 4600);
DISPLAY 0.680851 (-8525 4600);
DISPLAY INVISIBLE (-8525 4600);
FORCEPROP 1 LASTPIN (-8575 4525) $PN 1
J 0
(-8570 4487);
DISPLAY 0.787234 (-8570 4487);
PAINT MONO (-8570 4487);
FORCEPROP 1 LASTPIN (-8575 4325) $PN 2
J 0
(-8570 4335);
DISPLAY 0.787234 (-8570 4335);
PAINT MONO (-8570 4335);
FORCEPROP 1 LAST TOLERANCE 5%
J 0
(-8530 4450);
DISPLAY 0.787234 (-8530 4450);
FORCEPROP 1 LAST MATERIAL EMPTY
J 0
(-8535 4350);
DISPLAY 0.787234 (-8535 4350);
FORCEPROP 1 LAST WATTAGE 1/16W
J 0
(-8535 4400);
DISPLAY 0.787234 (-8535 4400);
FORCEPROP 1 LAST VALUE 51
J 0
(-8530 4500);
DISPLAY 0.787234 (-8530 4500);
FORCEPROP 1 LAST PACK_TYPE 0402LF
J 0
(-8535 4250);
DISPLAY 0.787234 (-8535 4250);
FORCEPROP 2 LAST CDS_LIB pure_quanta
J 2
(-8575 4425);
DISPLAY INVISIBLE (-8575 4425);
FORCEPROP 1 LAST PATH I146
J 0
(-8525 4600);
DISPLAY 0.978723 (-8525 4600);
PAINT WHITE (-8525 4600);
DISPLAY INVISIBLE (-8525 4600);
FORCEPROP 1 LAST PART_NUMBER CS05102JB04
J 0
(-8535 4300);
DISPLAY 0.787234 (-8535 4300);
DISPLAY INVISIBLE (-8535 4300);
FORCEADD Q_CAP..2
(-3125 2100);
FORCEPROP 1 LAST LOCATION C6018
J 1
(-3350 2100);
DISPLAY 0.638298 (-3350 2100);
FORCEPROP 0 LAST $SEC 1
J 0
(-3125 2375);
DISPLAY 0.680851 (-3125 2375);
PAINT MONO (-3125 2375);
DISPLAY INVISIBLE (-3125 2375);
FORCEPROP 0 LAST CDS_SEC 1
J 0
(-3125 2375);
DISPLAY 0.680851 (-3125 2375);
DISPLAY INVISIBLE (-3125 2375);
FORCEPROP 1 LASTPIN (-3225 2100) $PN 1
J 0
(-3235 2115);
DISPLAY 0.787234 (-3235 2115);
PAINT MONO (-3235 2115);
FORCEPROP 1 LASTPIN (-3025 2100) $PN 2
J 0
(-3040 2115);
DISPLAY 0.787234 (-3040 2115);
PAINT MONO (-3040 2115);
FORCEPROP 1 LAST VOLTAGE 25V
J 0
(-3100 2325);
DISPLAY 0.638298 (-3100 2325);
FORCEPROP 1 LAST MATERIAL X7R
J 0
(-3000 2325);
DISPLAY 0.638298 (-3000 2325);
FORCEPROP 0 LAST ROOM USB3_HUB2
J 0
(-3250 2025);
DISPLAY 0.680851 (-3250 2025);
FORCEPROP 1 LAST TOLERANCE 10%
J 2
(-3000 2275);
DISPLAY 0.638298 (-3000 2275);
FORCEPROP 1 LAST PACK_TYPE 0402
J 1
(-3175 2275);
DISPLAY 0.638298 (-3175 2275);
FORCEPROP 1 LAST VALUE 0.1UF
J 2
(-3100 2325);
DISPLAY 0.638298 (-3100 2325);
FORCEPROP 2 LAST CDS_LIB pure_quanta
J 0
(-3125 2100);
DISPLAY INVISIBLE (-3125 2100);
FORCEPROP 1 LAST PATH I147
J 0
(-3125 2300);
DISPLAY 0.978723 (-3125 2300);
PAINT WHITE (-3125 2300);
DISPLAY INVISIBLE (-3125 2300);
FORCEPROP 1 LAST PART_NUMBER CH4104K1B00
J 1
(-3125 2375);
DISPLAY 0.510638 (-3125 2375);
DISPLAY INVISIBLE (-3125 2375);
FORCEADD Q_CAP..2
(-3125 2150);
FORCEPROP 1 LAST LOCATION C6017
J 1
(-3350 2150);
DISPLAY 0.638298 (-3350 2150);
FORCEPROP 0 LAST $SEC 1
J 0
(-3300 2200);
DISPLAY 0.680851 (-3300 2200);
PAINT MONO (-3300 2200);
DISPLAY INVISIBLE (-3300 2200);
FORCEPROP 0 LAST CDS_SEC 1
J 0
(-3300 2200);
DISPLAY 0.680851 (-3300 2200);
DISPLAY INVISIBLE (-3300 2200);
FORCEPROP 1 LASTPIN (-3225 2150) $PN 1
J 0
(-3235 2165);
DISPLAY 0.787234 (-3235 2165);
PAINT MONO (-3235 2165);
FORCEPROP 1 LASTPIN (-3025 2150) $PN 2
J 0
(-3040 2165);
DISPLAY 0.787234 (-3040 2165);
PAINT MONO (-3040 2165);
FORCEPROP 0 LAST ROOM USB3_HUB2
J 0
(-3275 2225);
DISPLAY 0.680851 (-3275 2225);
FORCEPROP 2 LAST CDS_LIB pure_quanta
J 0
(-3125 2150);
DISPLAY INVISIBLE (-3125 2150);
FORCEPROP 1 LAST MATERIAL X7R
J 0
(-3100 1900);
DISPLAY 0.638298 (-3100 1900);
DISPLAY INVISIBLE (-3100 1900);
FORCEPROP 1 LAST PACK_TYPE 0402
J 1
(-3100 1850);
DISPLAY 0.638298 (-3100 1850);
DISPLAY INVISIBLE (-3100 1850);
FORCEPROP 1 LAST TOLERANCE 10%
J 2
(-3100 1900);
DISPLAY 0.638298 (-3100 1900);
DISPLAY INVISIBLE (-3100 1900);
FORCEPROP 1 LAST VALUE 0.1UF
J 2
(-3100 1950);
DISPLAY 0.638298 (-3100 1950);
DISPLAY INVISIBLE (-3100 1950);
FORCEPROP 1 LAST VOLTAGE 25V
J 0
(-3100 1950);
DISPLAY 0.638298 (-3100 1950);
DISPLAY INVISIBLE (-3100 1950);
FORCEPROP 1 LAST PATH I148
J 0
(-3125 2350);
DISPLAY 0.978723 (-3125 2350);
PAINT WHITE (-3125 2350);
DISPLAY INVISIBLE (-3125 2350);
FORCEPROP 1 LAST PART_NUMBER CH4104K1B00
J 1
(-3100 1825);
DISPLAY 0.510638 (-3100 1825);
DISPLAY INVISIBLE (-3100 1825);
FORCEADD OFFPAGE..3
(-5875 5650);
FORCEPROP 2 LAST $XR0 178 
J 0
(-5661 5650);
DISPLAY 0.638298 (-5661 5650);
PAINT MONO (-5661 5650);
FORCEPROP 2 LAST CDS_LIB standard
J 0
(-5875 5650);
DISPLAY INVISIBLE (-5875 5650);
FORCEPROP 1 LAST OFFPAGE TRUE
J 0
(-5550 5525);
DISPLAY 0.872340 (-5550 5525);
PAINT GREEN (-5550 5525);
DISPLAY INVISIBLE (-5550 5525);
FORCEPROP 1 LAST COMMENT_BODY TRUE
J 0
(-5925 5550);
DISPLAY 0.872340 (-5925 5550);
PAINT GREEN (-5925 5550);
DISPLAY INVISIBLE (-5925 5550);
FORCEPROP 2 LAST PATH I15
J 0
(-5675 5725);
DISPLAY 0.680851 (-5675 5725);
DISPLAY INVISIBLE (-5675 5725);
FORCEADD OFFPAGE..3
(-5875 5600);
FORCEPROP 2 LAST $XR0 178 
J 0
(-5661 5600);
DISPLAY 0.638298 (-5661 5600);
PAINT MONO (-5661 5600);
FORCEPROP 2 LAST CDS_LIB standard
J 0
(-5875 5600);
DISPLAY INVISIBLE (-5875 5600);
FORCEPROP 1 LAST OFFPAGE TRUE
J 0
(-5550 5475);
DISPLAY 0.872340 (-5550 5475);
PAINT GREEN (-5550 5475);
DISPLAY INVISIBLE (-5550 5475);
FORCEPROP 1 LAST COMMENT_BODY TRUE
J 0
(-5925 5500);
DISPLAY 0.872340 (-5925 5500);
PAINT GREEN (-5925 5500);
DISPLAY INVISIBLE (-5925 5500);
FORCEPROP 2 LAST PATH I16
J 0
(-5675 5675);
DISPLAY 0.680851 (-5675 5675);
DISPLAY INVISIBLE (-5675 5675);
FORCEADD Q_RES..1
(-7525 5650);
FORCEPROP 1 LAST LOCATION R6192
J 0
(-7775 5650);
DISPLAY 0.808511 (-7775 5650);
FORCEPROP 0 LAST $SEC 1
J 0
(-7175 5700);
DISPLAY 0.680851 (-7175 5700);
PAINT MONO (-7175 5700);
DISPLAY INVISIBLE (-7175 5700);
FORCEPROP 0 LAST CDS_SEC 1
J 0
(-7175 5700);
DISPLAY 0.680851 (-7175 5700);
DISPLAY INVISIBLE (-7175 5700);
FORCEPROP 1 LASTPIN (-7625 5650) $PN 1
J 0
(-7613 5662);
DISPLAY 0.787234 (-7613 5662);
PAINT MONO (-7613 5662);
FORCEPROP 1 LASTPIN (-7425 5650) $PN 2
J 0
(-7463 5662);
DISPLAY 0.787234 (-7463 5662);
PAINT MONO (-7463 5662);
FORCEPROP 0 LAST ROOM USB3_HUB2
J 0
(-7675 5725);
DISPLAY 0.680851 (-7675 5725);
FORCEPROP 1 LAST PACK_TYPE 0201LF
J 0
(-7100 5650);
DISPLAY 0.808511 (-7100 5650);
FORCEPROP 1 LAST VALUE 0
J 2
(-7350 5650);
DISPLAY 0.808511 (-7350 5650);
FORCEPROP 1 LAST MATERIAL CHIP
J 0
(-7300 5650);
DISPLAY 0.808511 (-7300 5650);
FORCEPROP 2 LAST CDS_LIB pure_quanta
J 0
(-7525 5650);
DISPLAY INVISIBLE (-7525 5650);
FORCEPROP 1 LAST TOLERANCE 5%
J 0
(-7700 5775);
DISPLAY 0.978723 (-7700 5775);
DISPLAY INVISIBLE (-7700 5775);
FORCEPROP 1 LAST WATTAGE 1/20W
J 2
(-7250 5775);
DISPLAY 0.978723 (-7250 5775);
DISPLAY INVISIBLE (-7250 5775);
FORCEPROP 1 LAST PATH I3
J 0
(-7575 5800);
DISPLAY 0.978723 (-7575 5800);
PAINT WHITE (-7575 5800);
DISPLAY INVISIBLE (-7575 5800);
FORCEPROP 1 LAST PART_NUMBER CS00001JE10
J 0
(-7750 5825);
DISPLAY 0.978723 (-7750 5825);
DISPLAY INVISIBLE (-7750 5825);
FORCEADD OFFPAGE..1
(-8725 4800);
FORCEPROP 2 LAST $XR0 29 
J 0
(-8976 4800);
DISPLAY 0.638298 (-8976 4800);
PAINT MONO (-8976 4800);
FORCEPROP 2 LAST CDS_LIB standard
J 0
(-8725 4800);
DISPLAY INVISIBLE (-8725 4800);
FORCEPROP 1 LAST OFFPAGE TRUE
J 0
(-8400 4675);
DISPLAY 0.872340 (-8400 4675);
PAINT GREEN (-8400 4675);
DISPLAY INVISIBLE (-8400 4675);
FORCEPROP 1 LAST COMMENT_BODY TRUE
J 0
(-8600 4700);
DISPLAY 0.872340 (-8600 4700);
PAINT GREEN (-8600 4700);
DISPLAY INVISIBLE (-8600 4700);
FORCEPROP 2 LAST PATH I39
J 0
(-8675 4875);
DISPLAY 0.680851 (-8675 4875);
DISPLAY INVISIBLE (-8675 4875);
FORCEADD Q_RES..1
(-7525 5600);
FORCEPROP 1 LAST LOCATION R6193
J 0
(-7775 5600);
DISPLAY 0.808511 (-7775 5600);
FORCEPROP 0 LAST $SEC 1
J 0
(-7175 5650);
DISPLAY 0.680851 (-7175 5650);
PAINT MONO (-7175 5650);
DISPLAY INVISIBLE (-7175 5650);
FORCEPROP 0 LAST CDS_SEC 1
J 0
(-7175 5650);
DISPLAY 0.680851 (-7175 5650);
DISPLAY INVISIBLE (-7175 5650);
FORCEPROP 1 LASTPIN (-7625 5600) $PN 1
J 0
(-7613 5612);
DISPLAY 0.787234 (-7613 5612);
PAINT MONO (-7613 5612);
FORCEPROP 1 LASTPIN (-7425 5600) $PN 2
J 0
(-7463 5612);
DISPLAY 0.787234 (-7463 5612);
PAINT MONO (-7463 5612);
FORCEPROP 0 LAST ROOM USB3_HUB2
J 0
(-7675 5525);
DISPLAY 0.680851 (-7675 5525);
FORCEPROP 1 LAST MATERIAL CHIP
J 0
(-7300 5600);
DISPLAY 0.808511 (-7300 5600);
FORCEPROP 1 LAST VALUE 0
J 2
(-7350 5600);
DISPLAY 0.808511 (-7350 5600);
FORCEPROP 1 LAST PACK_TYPE 0201LF
J 0
(-7100 5600);
DISPLAY 0.808511 (-7100 5600);
FORCEPROP 2 LAST CDS_LIB pure_quanta
J 0
(-7525 5600);
DISPLAY INVISIBLE (-7525 5600);
FORCEPROP 1 LAST WATTAGE 1/20W
J 2
(-7250 5725);
DISPLAY 0.978723 (-7250 5725);
DISPLAY INVISIBLE (-7250 5725);
FORCEPROP 1 LAST TOLERANCE 5%
J 0
(-7700 5725);
DISPLAY 0.978723 (-7700 5725);
DISPLAY INVISIBLE (-7700 5725);
FORCEPROP 1 LAST PATH I4
J 0
(-7575 5750);
DISPLAY 0.978723 (-7575 5750);
PAINT WHITE (-7575 5750);
DISPLAY INVISIBLE (-7575 5750);
FORCEPROP 1 LAST PART_NUMBER CS00001JE10
J 0
(-7750 5775);
DISPLAY 0.978723 (-7750 5775);
DISPLAY INVISIBLE (-7750 5775);
FORCEADD OFFPAGE..1
(-8725 4750);
FORCEPROP 2 LAST $XR0 29 
J 0
(-8976 4750);
DISPLAY 0.638298 (-8976 4750);
PAINT MONO (-8976 4750);
FORCEPROP 2 LAST CDS_LIB standard
J 0
(-8725 4750);
DISPLAY INVISIBLE (-8725 4750);
FORCEPROP 1 LAST OFFPAGE TRUE
J 0
(-8400 4625);
DISPLAY 0.872340 (-8400 4625);
PAINT GREEN (-8400 4625);
DISPLAY INVISIBLE (-8400 4625);
FORCEPROP 1 LAST COMMENT_BODY TRUE
J 0
(-8600 4650);
DISPLAY 0.872340 (-8600 4650);
PAINT GREEN (-8600 4650);
DISPLAY INVISIBLE (-8600 4650);
FORCEPROP 2 LAST PATH I40
J 0
(-8675 4825);
DISPLAY 0.680851 (-8675 4825);
DISPLAY INVISIBLE (-8675 4825);
FORCEADD OFFPAGE..2
(-6000 4800);
FORCEPROP 2 LAST $XR0 176 
J 0
(-5811 4800);
DISPLAY 0.638298 (-5811 4800);
PAINT MONO (-5811 4800);
FORCEPROP 2 LAST CDS_LIB standard
J 0
(-6000 4800);
DISPLAY INVISIBLE (-6000 4800);
FORCEPROP 1 LAST OFFPAGE TRUE
J 0
(-5675 4675);
DISPLAY 0.872340 (-5675 4675);
PAINT GREEN (-5675 4675);
DISPLAY INVISIBLE (-5675 4675);
FORCEPROP 1 LAST COMMENT_BODY TRUE
J 0
(-6045 4705);
DISPLAY 0.872340 (-6045 4705);
PAINT GREEN (-6045 4705);
DISPLAY INVISIBLE (-6045 4705);
FORCEPROP 2 LAST PATH I41
J 0
(-5825 4875);
DISPLAY 0.680851 (-5825 4875);
DISPLAY INVISIBLE (-5825 4875);
FORCEADD OFFPAGE..2
(-6000 4750);
FORCEPROP 2 LAST $XR0 176 
J 0
(-5811 4750);
DISPLAY 0.638298 (-5811 4750);
PAINT MONO (-5811 4750);
FORCEPROP 2 LAST CDS_LIB standard
J 0
(-6000 4750);
DISPLAY INVISIBLE (-6000 4750);
FORCEPROP 1 LAST OFFPAGE TRUE
J 0
(-5675 4625);
DISPLAY 0.872340 (-5675 4625);
PAINT GREEN (-5675 4625);
DISPLAY INVISIBLE (-5675 4625);
FORCEPROP 1 LAST COMMENT_BODY TRUE
J 0
(-6045 4655);
DISPLAY 0.872340 (-6045 4655);
PAINT GREEN (-6045 4655);
DISPLAY INVISIBLE (-6045 4655);
FORCEPROP 2 LAST PATH I42
J 0
(-5825 4825);
DISPLAY 0.680851 (-5825 4825);
DISPLAY INVISIBLE (-5825 4825);
FORCEADD OFFPAGE..2
(-5975 4450);
FORCEPROP 2 LAST $XR0 178 
J 0
(-5786 4450);
DISPLAY 0.638298 (-5786 4450);
PAINT MONO (-5786 4450);
FORCEPROP 2 LAST CDS_LIB standard
J 0
(-5975 4450);
DISPLAY INVISIBLE (-5975 4450);
FORCEPROP 1 LAST OFFPAGE TRUE
J 0
(-5650 4325);
DISPLAY 0.872340 (-5650 4325);
PAINT GREEN (-5650 4325);
DISPLAY INVISIBLE (-5650 4325);
FORCEPROP 1 LAST COMMENT_BODY TRUE
J 0
(-6020 4355);
DISPLAY 0.872340 (-6020 4355);
PAINT GREEN (-6020 4355);
DISPLAY INVISIBLE (-6020 4355);
FORCEPROP 2 LAST PATH I43
J 0
(-5800 4525);
DISPLAY 0.680851 (-5800 4525);
DISPLAY INVISIBLE (-5800 4525);
FORCEADD OFFPAGE..2
(-5975 4400);
FORCEPROP 2 LAST $XR0 178 
J 0
(-5786 4400);
DISPLAY 0.638298 (-5786 4400);
PAINT MONO (-5786 4400);
FORCEPROP 2 LAST CDS_LIB standard
J 0
(-5975 4400);
DISPLAY INVISIBLE (-5975 4400);
FORCEPROP 1 LAST OFFPAGE TRUE
J 0
(-5650 4275);
DISPLAY 0.872340 (-5650 4275);
PAINT GREEN (-5650 4275);
DISPLAY INVISIBLE (-5650 4275);
FORCEPROP 1 LAST COMMENT_BODY TRUE
J 0
(-6020 4305);
DISPLAY 0.872340 (-6020 4305);
PAINT GREEN (-6020 4305);
DISPLAY INVISIBLE (-6020 4305);
FORCEPROP 2 LAST PATH I44
J 0
(-5800 4475);
DISPLAY 0.680851 (-5800 4475);
DISPLAY INVISIBLE (-5800 4475);
FORCEADD OFFPAGE..1
(-4325 2675);
FORCEPROP 2 LAST $XR0 176 
J 0
(-4577 2675);
DISPLAY 0.638298 (-4577 2675);
PAINT MONO (-4577 2675);
FORCEPROP 2 LAST CDS_LIB standard
J 0
(-4325 2675);
DISPLAY INVISIBLE (-4325 2675);
FORCEPROP 1 LAST OFFPAGE TRUE
J 0
(-4000 2550);
DISPLAY 0.872340 (-4000 2550);
PAINT GREEN (-4000 2550);
DISPLAY INVISIBLE (-4000 2550);
FORCEPROP 1 LAST COMMENT_BODY TRUE
J 0
(-4200 2575);
DISPLAY 0.872340 (-4200 2575);
PAINT GREEN (-4200 2575);
DISPLAY INVISIBLE (-4200 2575);
FORCEPROP 2 LAST PATH I45
J 0
(-4275 2750);
DISPLAY 0.680851 (-4275 2750);
DISPLAY INVISIBLE (-4275 2750);
FORCEADD OFFPAGE..1
(-4325 2725);
FORCEPROP 2 LAST $XR0 176 
J 0
(-4577 2725);
DISPLAY 0.638298 (-4577 2725);
PAINT MONO (-4577 2725);
FORCEPROP 2 LAST CDS_LIB standard
J 0
(-4325 2725);
DISPLAY INVISIBLE (-4325 2725);
FORCEPROP 1 LAST OFFPAGE TRUE
J 0
(-4000 2600);
DISPLAY 0.872340 (-4000 2600);
PAINT GREEN (-4000 2600);
DISPLAY INVISIBLE (-4000 2600);
FORCEPROP 1 LAST COMMENT_BODY TRUE
J 0
(-4200 2625);
DISPLAY 0.872340 (-4200 2625);
PAINT GREEN (-4200 2625);
DISPLAY INVISIBLE (-4200 2625);
FORCEPROP 2 LAST PATH I46
J 0
(-4275 2800);
DISPLAY 0.680851 (-4275 2800);
DISPLAY INVISIBLE (-4275 2800);
FORCEADD OFFPAGE..1
(-4300 2100);
FORCEPROP 2 LAST $XR0 178 
J 0
(-4552 2100);
DISPLAY 0.638298 (-4552 2100);
PAINT MONO (-4552 2100);
FORCEPROP 2 LAST CDS_LIB standard
J 0
(-4300 2100);
DISPLAY INVISIBLE (-4300 2100);
FORCEPROP 1 LAST OFFPAGE TRUE
J 0
(-3975 1975);
DISPLAY 0.872340 (-3975 1975);
PAINT GREEN (-3975 1975);
DISPLAY INVISIBLE (-3975 1975);
FORCEPROP 1 LAST COMMENT_BODY TRUE
J 0
(-4175 2000);
DISPLAY 0.872340 (-4175 2000);
PAINT GREEN (-4175 2000);
DISPLAY INVISIBLE (-4175 2000);
FORCEPROP 2 LAST PATH I47
J 0
(-4250 2175);
DISPLAY 0.680851 (-4250 2175);
DISPLAY INVISIBLE (-4250 2175);
FORCEADD OFFPAGE..1
(-4300 2150);
FORCEPROP 2 LAST $XR0 178 
J 0
(-4552 2150);
DISPLAY 0.638298 (-4552 2150);
PAINT MONO (-4552 2150);
FORCEPROP 2 LAST CDS_LIB standard
J 0
(-4300 2150);
DISPLAY INVISIBLE (-4300 2150);
FORCEPROP 1 LAST OFFPAGE TRUE
J 0
(-3975 2025);
DISPLAY 0.872340 (-3975 2025);
PAINT GREEN (-3975 2025);
DISPLAY INVISIBLE (-3975 2025);
FORCEPROP 1 LAST COMMENT_BODY TRUE
J 0
(-4175 2050);
DISPLAY 0.872340 (-4175 2050);
PAINT GREEN (-4175 2050);
DISPLAY INVISIBLE (-4175 2050);
FORCEPROP 2 LAST PATH I48
J 0
(-4250 2225);
DISPLAY 0.680851 (-4250 2225);
DISPLAY INVISIBLE (-4250 2225);
FORCEADD Q_CAP_DIFFBUS..2
(-3175 2725);
FORCEPROP 1 LAST LOCATION C6015
J 0
(-3450 2725);
DISPLAY 0.723404 (-3450 2725);
PAINT GREEN (-3450 2725);
FORCEPROP 0 LAST $SEC 1
J 0
(-3200 2925);
DISPLAY 0.680851 (-3200 2925);
PAINT MONO (-3200 2925);
DISPLAY INVISIBLE (-3200 2925);
FORCEPROP 0 LAST CDS_SEC 1
J 0
(-3200 2925);
DISPLAY 0.680851 (-3200 2925);
DISPLAY INVISIBLE (-3200 2925);
FORCEPROP 0 LASTPIN (-3250 2725) $PN 1
J 2
(-3260 2735);
DISPLAY 0.680851 (-3260 2735);
PAINT MONO (-3260 2735);
FORCEPROP 0 LASTPIN (-3100 2725) $PN 2
J 0
(-3090 2735);
DISPLAY 0.680851 (-3090 2735);
PAINT MONO (-3090 2735);
FORCEPROP 0 LAST ROOM USB3_HUB1
J 0
(-3300 2800);
DISPLAY 0.680851 (-3300 2800);
FORCEPROP 1 LAST MATERIAL X6S
J 0
(-3200 2925);
DISPLAY 0.723404 (-3200 2925);
PAINT GREEN (-3200 2925);
FORCEPROP 2 LAST PACK_TYPE C0402
J 0
(-3191 3021);
DISPLAY 0.680851 (-3191 3021);
FORCEPROP 2 LAST TOLERANCE 10%
J 0
(-2866 2921);
DISPLAY 0.680851 (-2866 2921);
FORCEPROP 2 LAST VOLTAGE 6.3V
J 0
(-3041 2921);
DISPLAY 0.680851 (-3041 2921);
FORCEPROP 2 LAST VALUE DIFF BUS_0.33UF
J 0
(-2950 2725);
DISPLAY 0.680851 (-2950 2725);
FORCEPROP 1 LAST PIN_NAMES_ROTATE True
J 0
(-3175 2725);
DISPLAY 0.489362 (-3175 2725);
PAINT GREEN (-3175 2725);
DISPLAY INVISIBLE (-3175 2725);
FORCEPROP 2 LAST CDS_LIB pure_quanta
J 0
(-3175 2725);
DISPLAY INVISIBLE (-3175 2725);
FORCEPROP 1 LAST CDS_LMAN_SYM_OUTLINE -25,50,25,-50
J 0
(-3175 2725);
DISPLAY 0.468085 (-3175 2725);
PAINT GREEN (-3175 2725);
DISPLAY INVISIBLE (-3175 2725);
FORCEPROP 1 LAST PATH I49
J 0
(-3175 2725);
DISPLAY 0.723404 (-3175 2725);
DISPLAY INVISIBLE (-3175 2725);
FORCEPROP 1 LAST PART_NUMBER SP_CH4331KEB01
J 0
(-3200 2984);
DISPLAY 0.723404 (-3200 2984);
PAINT GREEN (-3200 2984);
DISPLAY INVISIBLE (-3200 2984);
FORCEADD Q_RES..1
(-7550 5950);
FORCEPROP 1 LAST LOCATION R6191
J 0
(-7800 5950);
DISPLAY 0.808511 (-7800 5950);
FORCEPROP 0 LAST $SEC 1
J 0
(-7150 6000);
DISPLAY 0.680851 (-7150 6000);
PAINT MONO (-7150 6000);
DISPLAY INVISIBLE (-7150 6000);
FORCEPROP 0 LAST CDS_SEC 1
J 0
(-7150 6000);
DISPLAY 0.680851 (-7150 6000);
DISPLAY INVISIBLE (-7150 6000);
FORCEPROP 1 LASTPIN (-7650 5950) $PN 1
J 0
(-7638 5962);
DISPLAY 0.787234 (-7638 5962);
PAINT MONO (-7638 5962);
FORCEPROP 1 LASTPIN (-7450 5950) $PN 2
J 0
(-7488 5962);
DISPLAY 0.787234 (-7488 5962);
PAINT MONO (-7488 5962);
FORCEPROP 0 LAST ROOM USB3_HUB1
J 0
(-7700 5900);
DISPLAY 0.680851 (-7700 5900);
FORCEPROP 1 LAST VALUE 0
J 2
(-7375 5950);
DISPLAY 0.808511 (-7375 5950);
FORCEPROP 1 LAST MATERIAL CHIP
J 0
(-7300 5950);
DISPLAY 0.808511 (-7300 5950);
FORCEPROP 1 LAST PACK_TYPE 0201LF
J 0
(-7100 5950);
DISPLAY 0.808511 (-7100 5950);
FORCEPROP 1 LAST TOLERANCE 5%
J 0
(-7725 6075);
DISPLAY 0.978723 (-7725 6075);
DISPLAY INVISIBLE (-7725 6075);
FORCEPROP 1 LAST WATTAGE 1/20W
J 2
(-7275 6075);
DISPLAY 0.978723 (-7275 6075);
DISPLAY INVISIBLE (-7275 6075);
FORCEPROP 2 LAST CDS_LIB pure_quanta
J 0
(-7550 5950);
DISPLAY INVISIBLE (-7550 5950);
FORCEPROP 1 LAST PATH I5
J 0
(-7600 6100);
DISPLAY 0.978723 (-7600 6100);
PAINT WHITE (-7600 6100);
DISPLAY INVISIBLE (-7600 6100);
FORCEPROP 1 LAST PART_NUMBER CS00001JE10
J 0
(-7775 6125);
DISPLAY 0.978723 (-7775 6125);
DISPLAY INVISIBLE (-7775 6125);
FORCEADD Q_CAP_DIFFBUS..2
(-3175 2675);
FORCEPROP 1 LAST LOCATION C6016
J 0
(-3450 2675);
DISPLAY 0.723404 (-3450 2675);
PAINT GREEN (-3450 2675);
FORCEPROP 0 LAST $SEC 1
J 0
(-3075 2725);
DISPLAY 0.680851 (-3075 2725);
PAINT MONO (-3075 2725);
DISPLAY INVISIBLE (-3075 2725);
FORCEPROP 0 LAST CDS_SEC 1
J 0
(-3075 2725);
DISPLAY 0.680851 (-3075 2725);
DISPLAY INVISIBLE (-3075 2725);
FORCEPROP 0 LASTPIN (-3250 2675) $PN 1
J 2
(-3260 2685);
DISPLAY 0.680851 (-3260 2685);
PAINT MONO (-3260 2685);
FORCEPROP 0 LASTPIN (-3100 2675) $PN 2
J 0
(-3090 2685);
DISPLAY 0.680851 (-3090 2685);
PAINT MONO (-3090 2685);
FORCEPROP 0 LAST ROOM USB3_HUB1
J 0
(-3325 2600);
DISPLAY 0.680851 (-3325 2600);
FORCEPROP 2 LAST VALUE DIFF BUS_0.33UF
J 0
(-2950 2675);
DISPLAY 0.680851 (-2950 2675);
FORCEPROP 2 LAST CDS_LIB pure_quanta
J 0
(-3175 2675);
DISPLAY INVISIBLE (-3175 2675);
FORCEPROP 1 LAST CDS_LMAN_SYM_OUTLINE -25,50,25,-50
J 0
(-3175 2675);
DISPLAY 0.468085 (-3175 2675);
PAINT GREEN (-3175 2675);
DISPLAY INVISIBLE (-3175 2675);
FORCEPROP 0 LAST TOLERANCE 10%
J 0
(-2875 2725);
DISPLAY 0.680851 (-2875 2725);
DISPLAY INVISIBLE (-2875 2725);
FORCEPROP 0 LAST VOLTAGE 6.3V
J 0
(-3050 2725);
DISPLAY 0.680851 (-3050 2725);
DISPLAY INVISIBLE (-3050 2725);
FORCEPROP 1 LAST MATERIAL X6S
J 0
(-3209 2729);
DISPLAY 0.723404 (-3209 2729);
PAINT GREEN (-3209 2729);
DISPLAY INVISIBLE (-3209 2729);
FORCEPROP 0 LAST PACK_TYPE C0402
J 0
(-3200 2825);
DISPLAY 0.680851 (-3200 2825);
DISPLAY INVISIBLE (-3200 2825);
FORCEPROP 1 LAST PIN_NAMES_ROTATE True
J 0
(-3175 2675);
DISPLAY 0.489362 (-3175 2675);
PAINT GREEN (-3175 2675);
DISPLAY INVISIBLE (-3175 2675);
FORCEPROP 1 LAST PATH I50
J 0
(-3175 2675);
DISPLAY 0.723404 (-3175 2675);
DISPLAY INVISIBLE (-3175 2675);
FORCEPROP 1 LAST PART_NUMBER SP_CH4331KEB01
J 0
(-3209 2788);
DISPLAY 0.723404 (-3209 2788);
PAINT GREEN (-3209 2788);
DISPLAY INVISIBLE (-3209 2788);
FORCEADD OFFPAGE..2
(-1375 2725);
FORCEPROP 2 LAST $XR0 29 
J 0
(-1186 2725);
DISPLAY 0.638298 (-1186 2725);
PAINT MONO (-1186 2725);
FORCEPROP 2 LAST CDS_LIB standard
J 0
(-1375 2725);
DISPLAY INVISIBLE (-1375 2725);
FORCEPROP 1 LAST OFFPAGE TRUE
J 0
(-1050 2600);
DISPLAY 0.872340 (-1050 2600);
PAINT GREEN (-1050 2600);
DISPLAY INVISIBLE (-1050 2600);
FORCEPROP 1 LAST COMMENT_BODY TRUE
J 0
(-1420 2630);
DISPLAY 0.872340 (-1420 2630);
PAINT GREEN (-1420 2630);
DISPLAY INVISIBLE (-1420 2630);
FORCEPROP 2 LAST PATH I53
J 0
(-1200 2800);
DISPLAY 0.680851 (-1200 2800);
DISPLAY INVISIBLE (-1200 2800);
FORCEADD OFFPAGE..2
(-1375 2675);
FORCEPROP 2 LAST $XR0 29 
J 0
(-1186 2675);
DISPLAY 0.638298 (-1186 2675);
PAINT MONO (-1186 2675);
FORCEPROP 2 LAST CDS_LIB standard
J 0
(-1375 2675);
DISPLAY INVISIBLE (-1375 2675);
FORCEPROP 1 LAST OFFPAGE TRUE
J 0
(-1050 2550);
DISPLAY 0.872340 (-1050 2550);
PAINT GREEN (-1050 2550);
DISPLAY INVISIBLE (-1050 2550);
FORCEPROP 1 LAST COMMENT_BODY TRUE
J 0
(-1420 2580);
DISPLAY 0.872340 (-1420 2580);
PAINT GREEN (-1420 2580);
DISPLAY INVISIBLE (-1420 2580);
FORCEPROP 2 LAST PATH I54
J 0
(-1200 2750);
DISPLAY 0.680851 (-1200 2750);
DISPLAY INVISIBLE (-1200 2750);
FORCEADD Q_RES..1
(-7550 6000);
FORCEPROP 1 LAST LOCATION R6190
J 0
(-7800 6000);
DISPLAY 0.808511 (-7800 6000);
FORCEPROP 0 LAST $SEC 1
J 0
(-7775 6175);
DISPLAY 0.680851 (-7775 6175);
PAINT MONO (-7775 6175);
DISPLAY INVISIBLE (-7775 6175);
FORCEPROP 0 LAST CDS_SEC 1
J 0
(-7775 6175);
DISPLAY 0.680851 (-7775 6175);
DISPLAY INVISIBLE (-7775 6175);
FORCEPROP 1 LASTPIN (-7650 6000) $PN 1
J 0
(-7638 6012);
DISPLAY 0.787234 (-7638 6012);
PAINT MONO (-7638 6012);
FORCEPROP 1 LASTPIN (-7450 6000) $PN 2
J 0
(-7488 6012);
DISPLAY 0.787234 (-7488 6012);
PAINT MONO (-7488 6012);
FORCEPROP 1 LAST MATERIAL CHIP
J 0
(-7300 6000);
DISPLAY 0.808511 (-7300 6000);
FORCEPROP 0 LAST ROOM USB3_HUB1
J 0
(-7700 6050);
DISPLAY 0.680851 (-7700 6050);
FORCEPROP 1 LAST WATTAGE 1/20W
J 2
(-7275 6175);
DISPLAY 0.808511 (-7275 6175);
FORCEPROP 1 LAST VALUE 0
J 2
(-7375 6000);
DISPLAY 0.808511 (-7375 6000);
FORCEPROP 1 LAST TOLERANCE 5%
J 0
(-7725 6175);
DISPLAY 0.808511 (-7725 6175);
FORCEPROP 1 LAST PACK_TYPE 0201LF
J 0
(-7100 6000);
DISPLAY 0.808511 (-7100 6000);
FORCEPROP 2 LAST CDS_LIB pure_quanta
J 0
(-7550 6000);
DISPLAY INVISIBLE (-7550 6000);
FORCEPROP 1 LAST PATH I6
J 0
(-7600 6150);
DISPLAY 0.978723 (-7600 6150);
PAINT WHITE (-7600 6150);
DISPLAY INVISIBLE (-7600 6150);
FORCEPROP 1 LAST PART_NUMBER CS00001JE10
J 0
(-7775 6225);
DISPLAY 0.808511 (-7775 6225);
DISPLAY INVISIBLE (-7775 6225);
FORCEADD OFFPAGE..3
R 2
(-4150 5950);
FORCEPROP 2 LAST $XR0 176 
J 0
(-4460 5950);
DISPLAY 0.638298 (-4460 5950);
PAINT MONO (-4460 5950);
FORCEPROP 2 LAST CDS_LIB standard
J 0
(-4150 5950);
DISPLAY INVISIBLE (-4150 5950);
FORCEPROP 1 LAST OFFPAGE TRUE
J 2
(-4475 5825);
DISPLAY 0.872340 (-4475 5825);
PAINT GREEN (-4475 5825);
DISPLAY INVISIBLE (-4475 5825);
FORCEPROP 1 LAST COMMENT_BODY TRUE
J 2
(-4100 5850);
DISPLAY 0.872340 (-4100 5850);
PAINT GREEN (-4100 5850);
DISPLAY INVISIBLE (-4100 5850);
FORCEPROP 2 LAST PATH I65
J 0
(-4100 6025);
DISPLAY 0.680851 (-4100 6025);
DISPLAY INVISIBLE (-4100 6025);
FORCEADD OFFPAGE..3
R 2
(-4150 6000);
FORCEPROP 2 LAST $XR0 176 
J 0
(-4460 6000);
DISPLAY 0.638298 (-4460 6000);
PAINT MONO (-4460 6000);
FORCEPROP 2 LAST CDS_LIB standard
J 0
(-4150 6000);
DISPLAY INVISIBLE (-4150 6000);
FORCEPROP 1 LAST OFFPAGE TRUE
J 2
(-4475 5875);
DISPLAY 0.872340 (-4475 5875);
PAINT GREEN (-4475 5875);
DISPLAY INVISIBLE (-4475 5875);
FORCEPROP 1 LAST COMMENT_BODY TRUE
J 2
(-4100 5900);
DISPLAY 0.872340 (-4100 5900);
PAINT GREEN (-4100 5900);
DISPLAY INVISIBLE (-4100 5900);
FORCEPROP 2 LAST PATH I66
J 0
(-4100 6075);
DISPLAY 0.680851 (-4100 6075);
DISPLAY INVISIBLE (-4100 6075);
FORCEADD OFFPAGE..3
R 2
(-4125 5375);
FORCEPROP 2 LAST $XR0 178 
J 0
(-4435 5375);
DISPLAY 0.638298 (-4435 5375);
PAINT MONO (-4435 5375);
FORCEPROP 2 LAST CDS_LIB standard
J 0
(-4125 5375);
DISPLAY INVISIBLE (-4125 5375);
FORCEPROP 1 LAST OFFPAGE TRUE
J 2
(-4450 5250);
DISPLAY 0.872340 (-4450 5250);
PAINT GREEN (-4450 5250);
DISPLAY INVISIBLE (-4450 5250);
FORCEPROP 1 LAST COMMENT_BODY TRUE
J 2
(-4075 5275);
DISPLAY 0.872340 (-4075 5275);
PAINT GREEN (-4075 5275);
DISPLAY INVISIBLE (-4075 5275);
FORCEPROP 2 LAST PATH I67
J 0
(-4075 5450);
DISPLAY 0.680851 (-4075 5450);
DISPLAY INVISIBLE (-4075 5450);
FORCEADD OFFPAGE..3
R 2
(-4125 5425);
FORCEPROP 2 LAST $XR0 178 
J 0
(-4435 5425);
DISPLAY 0.638298 (-4435 5425);
PAINT MONO (-4435 5425);
FORCEPROP 2 LAST CDS_LIB standard
J 0
(-4125 5425);
DISPLAY INVISIBLE (-4125 5425);
FORCEPROP 1 LAST OFFPAGE TRUE
J 2
(-4450 5300);
DISPLAY 0.872340 (-4450 5300);
PAINT GREEN (-4450 5300);
DISPLAY INVISIBLE (-4450 5300);
FORCEPROP 1 LAST COMMENT_BODY TRUE
J 2
(-4075 5325);
DISPLAY 0.872340 (-4075 5325);
PAINT GREEN (-4075 5325);
DISPLAY INVISIBLE (-4075 5325);
FORCEPROP 2 LAST PATH I68
J 0
(-4075 5500);
DISPLAY 0.680851 (-4075 5500);
DISPLAY INVISIBLE (-4075 5500);
FORCEADD OFFPAGE..3
(-1200 6000);
FORCEPROP 2 LAST $XR0 150 
J 0
(-986 6000);
DISPLAY 0.638298 (-986 6000);
PAINT MONO (-986 6000);
FORCEPROP 2 LAST CDS_LIB standard
J 0
(-1200 6000);
DISPLAY INVISIBLE (-1200 6000);
FORCEPROP 1 LAST OFFPAGE TRUE
J 0
(-875 5875);
DISPLAY 0.872340 (-875 5875);
PAINT GREEN (-875 5875);
DISPLAY INVISIBLE (-875 5875);
FORCEPROP 1 LAST COMMENT_BODY TRUE
J 0
(-1250 5900);
DISPLAY 0.872340 (-1250 5900);
PAINT GREEN (-1250 5900);
DISPLAY INVISIBLE (-1250 5900);
FORCEPROP 2 LAST PATH I69
J 0
(-1000 6075);
DISPLAY 0.680851 (-1000 6075);
DISPLAY INVISIBLE (-1000 6075);
FORCEADD OFFPAGE..3
(-1200 5950);
FORCEPROP 2 LAST $XR0 150 
J 0
(-986 5950);
DISPLAY 0.638298 (-986 5950);
PAINT MONO (-986 5950);
FORCEPROP 2 LAST CDS_LIB standard
J 0
(-1200 5950);
DISPLAY INVISIBLE (-1200 5950);
FORCEPROP 1 LAST OFFPAGE TRUE
J 0
(-875 5825);
DISPLAY 0.872340 (-875 5825);
PAINT GREEN (-875 5825);
DISPLAY INVISIBLE (-875 5825);
FORCEPROP 1 LAST COMMENT_BODY TRUE
J 0
(-1250 5850);
DISPLAY 0.872340 (-1250 5850);
PAINT GREEN (-1250 5850);
DISPLAY INVISIBLE (-1250 5850);
FORCEPROP 2 LAST PATH I70
J 0
(-1000 6025);
DISPLAY 0.680851 (-1000 6025);
DISPLAY INVISIBLE (-1000 6025);
FORCEADD Q_RES..1
(-2975 5950);
FORCEPROP 1 LAST LOCATION R6195
J 0
(-3250 5950);
DISPLAY 0.808511 (-3250 5950);
FORCEPROP 0 LAST $SEC 1
J 0
(-2575 6000);
DISPLAY 0.680851 (-2575 6000);
PAINT MONO (-2575 6000);
DISPLAY INVISIBLE (-2575 6000);
FORCEPROP 0 LAST CDS_SEC 1
J 0
(-2575 6000);
DISPLAY 0.680851 (-2575 6000);
DISPLAY INVISIBLE (-2575 6000);
FORCEPROP 1 LASTPIN (-3075 5950) $PN 1
J 0
(-3063 5962);
DISPLAY 0.787234 (-3063 5962);
PAINT MONO (-3063 5962);
FORCEPROP 1 LASTPIN (-2875 5950) $PN 2
J 0
(-2913 5962);
DISPLAY 0.787234 (-2913 5962);
PAINT MONO (-2913 5962);
FORCEPROP 1 LAST MATERIAL CHIP
J 0
(-2650 5950);
DISPLAY 0.808511 (-2650 5950);
FORCEPROP 1 LAST PACK_TYPE 0201LF
J 0
(-2450 5950);
DISPLAY 0.808511 (-2450 5950);
FORCEPROP 1 LAST VALUE 0
J 2
(-2775 5950);
DISPLAY 0.808511 (-2775 5950);
FORCEPROP 0 LAST ROOM USB3_HUB1
J 0
(-3125 5900);
DISPLAY 0.680851 (-3125 5900);
FORCEPROP 1 LAST WATTAGE 1/20W
J 2
(-2700 6075);
DISPLAY 0.978723 (-2700 6075);
DISPLAY INVISIBLE (-2700 6075);
FORCEPROP 1 LAST TOLERANCE 5%
J 0
(-3150 6075);
DISPLAY 0.978723 (-3150 6075);
DISPLAY INVISIBLE (-3150 6075);
FORCEPROP 2 LAST CDS_LIB pure_quanta
J 0
(-2975 5950);
DISPLAY INVISIBLE (-2975 5950);
FORCEPROP 1 LAST PATH I71
J 0
(-3025 6100);
DISPLAY 0.978723 (-3025 6100);
PAINT WHITE (-3025 6100);
DISPLAY INVISIBLE (-3025 6100);
FORCEPROP 1 LAST PART_NUMBER CS00001JE10
J 0
(-3200 6125);
DISPLAY 0.978723 (-3200 6125);
DISPLAY INVISIBLE (-3200 6125);
FORCEADD Q_RES..1
(-2975 6000);
FORCEPROP 1 LAST LOCATION R6194
J 0
(-3250 6000);
DISPLAY 0.808511 (-3250 6000);
FORCEPROP 0 LAST $SEC 1
J 0
(-3200 6175);
DISPLAY 0.680851 (-3200 6175);
PAINT MONO (-3200 6175);
DISPLAY INVISIBLE (-3200 6175);
FORCEPROP 0 LAST CDS_SEC 1
J 0
(-3200 6175);
DISPLAY 0.680851 (-3200 6175);
DISPLAY INVISIBLE (-3200 6175);
FORCEPROP 1 LASTPIN (-3075 6000) $PN 1
J 0
(-3063 6012);
DISPLAY 0.787234 (-3063 6012);
PAINT MONO (-3063 6012);
FORCEPROP 1 LASTPIN (-2875 6000) $PN 2
J 0
(-2913 6012);
DISPLAY 0.787234 (-2913 6012);
PAINT MONO (-2913 6012);
FORCEPROP 1 LAST PACK_TYPE 0201LF
J 0
(-2450 6000);
DISPLAY 0.808511 (-2450 6000);
FORCEPROP 1 LAST TOLERANCE 5%
J 0
(-3150 6175);
DISPLAY 0.808511 (-3150 6175);
FORCEPROP 1 LAST VALUE 0
J 2
(-2775 6000);
DISPLAY 0.808511 (-2775 6000);
FORCEPROP 1 LAST WATTAGE 1/20W
J 2
(-2700 6175);
DISPLAY 0.808511 (-2700 6175);
FORCEPROP 1 LAST MATERIAL CHIP
J 0
(-2650 6000);
DISPLAY 0.808511 (-2650 6000);
FORCEPROP 0 LAST ROOM USB3_HUB1
J 0
(-3125 6075);
DISPLAY 0.680851 (-3125 6075);
FORCEPROP 2 LAST CDS_LIB pure_quanta
J 0
(-2975 6000);
DISPLAY INVISIBLE (-2975 6000);
FORCEPROP 1 LAST PATH I72
J 0
(-3025 6150);
DISPLAY 0.978723 (-3025 6150);
PAINT WHITE (-3025 6150);
DISPLAY INVISIBLE (-3025 6150);
FORCEPROP 1 LAST PART_NUMBER CS00001JE10
J 0
(-3200 6225);
DISPLAY 0.808511 (-3200 6225);
DISPLAY INVISIBLE (-3200 6225);
FORCEADD Q_RES..1
(-2950 5425);
FORCEPROP 1 LAST LOCATION R6196
J 0
(-3225 5425);
DISPLAY 0.808511 (-3225 5425);
FORCEPROP 0 LAST $SEC 1
J 0
(-2550 5475);
DISPLAY 0.680851 (-2550 5475);
PAINT MONO (-2550 5475);
DISPLAY INVISIBLE (-2550 5475);
FORCEPROP 0 LAST CDS_SEC 1
J 0
(-2550 5475);
DISPLAY 0.680851 (-2550 5475);
DISPLAY INVISIBLE (-2550 5475);
FORCEPROP 1 LASTPIN (-3050 5425) $PN 1
J 0
(-3038 5437);
DISPLAY 0.787234 (-3038 5437);
PAINT MONO (-3038 5437);
FORCEPROP 1 LASTPIN (-2850 5425) $PN 2
J 0
(-2888 5437);
DISPLAY 0.787234 (-2888 5437);
PAINT MONO (-2888 5437);
FORCEPROP 1 LAST MATERIAL CHIP
J 0
(-2700 5425);
DISPLAY 0.808511 (-2700 5425);
FORCEPROP 1 LAST VALUE 0
J 2
(-2775 5425);
DISPLAY 0.808511 (-2775 5425);
FORCEPROP 1 LAST PACK_TYPE 0201LF
J 0
(-2475 5425);
DISPLAY 0.808511 (-2475 5425);
FORCEPROP 0 LAST ROOM USB3_HUB2
J 0
(-3100 5500);
DISPLAY 0.680851 (-3100 5500);
FORCEPROP 1 LAST WATTAGE 1/20W
J 2
(-2675 5550);
DISPLAY 0.978723 (-2675 5550);
DISPLAY INVISIBLE (-2675 5550);
FORCEPROP 1 LAST TOLERANCE 5%
J 0
(-3125 5550);
DISPLAY 0.978723 (-3125 5550);
DISPLAY INVISIBLE (-3125 5550);
FORCEPROP 2 LAST CDS_LIB pure_quanta
J 0
(-2950 5425);
DISPLAY INVISIBLE (-2950 5425);
FORCEPROP 1 LAST PATH I73
J 0
(-3000 5575);
DISPLAY 0.978723 (-3000 5575);
PAINT WHITE (-3000 5575);
DISPLAY INVISIBLE (-3000 5575);
FORCEPROP 1 LAST PART_NUMBER CS00001JE10
J 0
(-3175 5600);
DISPLAY 0.978723 (-3175 5600);
DISPLAY INVISIBLE (-3175 5600);
FORCEADD Q_RES..1
(-2950 5375);
FORCEPROP 1 LAST LOCATION R6197
J 0
(-3225 5375);
DISPLAY 0.808511 (-3225 5375);
FORCEPROP 0 LAST $SEC 1
J 0
(-2550 5425);
DISPLAY 0.680851 (-2550 5425);
PAINT MONO (-2550 5425);
DISPLAY INVISIBLE (-2550 5425);
FORCEPROP 0 LAST CDS_SEC 1
J 0
(-2550 5425);
DISPLAY 0.680851 (-2550 5425);
DISPLAY INVISIBLE (-2550 5425);
FORCEPROP 1 LASTPIN (-3050 5375) $PN 1
J 0
(-3038 5387);
DISPLAY 0.787234 (-3038 5387);
PAINT MONO (-3038 5387);
FORCEPROP 1 LASTPIN (-2850 5375) $PN 2
J 0
(-2888 5387);
DISPLAY 0.787234 (-2888 5387);
PAINT MONO (-2888 5387);
FORCEPROP 1 LAST VALUE 0
J 2
(-2775 5375);
DISPLAY 0.808511 (-2775 5375);
FORCEPROP 1 LAST PACK_TYPE 0201LF
J 0
(-2475 5375);
DISPLAY 0.808511 (-2475 5375);
FORCEPROP 1 LAST MATERIAL CHIP
J 0
(-2700 5375);
DISPLAY 0.808511 (-2700 5375);
FORCEPROP 0 LAST ROOM USB3_HUB2
J 0
(-3075 5325);
DISPLAY 0.680851 (-3075 5325);
FORCEPROP 1 LAST TOLERANCE 5%
J 0
(-3125 5500);
DISPLAY 0.978723 (-3125 5500);
DISPLAY INVISIBLE (-3125 5500);
FORCEPROP 1 LAST WATTAGE 1/20W
J 2
(-2675 5500);
DISPLAY 0.978723 (-2675 5500);
DISPLAY INVISIBLE (-2675 5500);
FORCEPROP 2 LAST CDS_LIB pure_quanta
J 0
(-2950 5375);
DISPLAY INVISIBLE (-2950 5375);
FORCEPROP 1 LAST PATH I74
J 0
(-3000 5525);
DISPLAY 0.978723 (-3000 5525);
PAINT WHITE (-3000 5525);
DISPLAY INVISIBLE (-3000 5525);
FORCEPROP 1 LAST PART_NUMBER CS00001JE10
J 0
(-3175 5550);
DISPLAY 0.978723 (-3175 5550);
DISPLAY INVISIBLE (-3175 5550);
FORCEADD OFFPAGE..2
(-5700 2650);
FORCEPROP 2 LAST $XR0 176 
J 0
(-5511 2650);
DISPLAY 0.638298 (-5511 2650);
PAINT MONO (-5511 2650);
FORCEPROP 2 LAST CDS_LIB standard
J 0
(-5700 2650);
DISPLAY INVISIBLE (-5700 2650);
FORCEPROP 1 LAST OFFPAGE TRUE
J 0
(-5375 2525);
DISPLAY 0.872340 (-5375 2525);
PAINT GREEN (-5375 2525);
DISPLAY INVISIBLE (-5375 2525);
FORCEPROP 1 LAST COMMENT_BODY TRUE
J 0
(-5745 2555);
DISPLAY 0.872340 (-5745 2555);
PAINT GREEN (-5745 2555);
DISPLAY INVISIBLE (-5745 2555);
FORCEPROP 2 LAST PATH I75
J 0
(-5525 2725);
DISPLAY 0.680851 (-5525 2725);
DISPLAY INVISIBLE (-5525 2725);
FORCEADD OFFPAGE..2
(-5700 2600);
FORCEPROP 2 LAST $XR0 176 
J 0
(-5511 2600);
DISPLAY 0.638298 (-5511 2600);
PAINT MONO (-5511 2600);
FORCEPROP 2 LAST CDS_LIB standard
J 0
(-5700 2600);
DISPLAY INVISIBLE (-5700 2600);
FORCEPROP 1 LAST OFFPAGE TRUE
J 0
(-5375 2475);
DISPLAY 0.872340 (-5375 2475);
PAINT GREEN (-5375 2475);
DISPLAY INVISIBLE (-5375 2475);
FORCEPROP 1 LAST COMMENT_BODY TRUE
J 0
(-5745 2505);
DISPLAY 0.872340 (-5745 2505);
PAINT GREEN (-5745 2505);
DISPLAY INVISIBLE (-5745 2505);
FORCEPROP 2 LAST PATH I76
J 0
(-5525 2675);
DISPLAY 0.680851 (-5525 2675);
DISPLAY INVISIBLE (-5525 2675);
FORCEADD OFFPAGE..2
(-5675 2300);
FORCEPROP 2 LAST $XR0 178 
J 0
(-5486 2300);
DISPLAY 0.638298 (-5486 2300);
PAINT MONO (-5486 2300);
FORCEPROP 2 LAST CDS_LIB standard
J 0
(-5675 2300);
DISPLAY INVISIBLE (-5675 2300);
FORCEPROP 1 LAST OFFPAGE TRUE
J 0
(-5350 2175);
DISPLAY 0.872340 (-5350 2175);
PAINT GREEN (-5350 2175);
DISPLAY INVISIBLE (-5350 2175);
FORCEPROP 1 LAST COMMENT_BODY TRUE
J 0
(-5720 2205);
DISPLAY 0.872340 (-5720 2205);
PAINT GREEN (-5720 2205);
DISPLAY INVISIBLE (-5720 2205);
FORCEPROP 2 LAST PATH I77
J 0
(-5500 2375);
DISPLAY 0.680851 (-5500 2375);
DISPLAY INVISIBLE (-5500 2375);
FORCEADD OFFPAGE..2
(-5675 2250);
FORCEPROP 2 LAST $XR0 178 
J 0
(-5486 2250);
DISPLAY 0.638298 (-5486 2250);
PAINT MONO (-5486 2250);
FORCEPROP 2 LAST CDS_LIB standard
J 0
(-5675 2250);
DISPLAY INVISIBLE (-5675 2250);
FORCEPROP 1 LAST OFFPAGE TRUE
J 0
(-5350 2125);
DISPLAY 0.872340 (-5350 2125);
PAINT GREEN (-5350 2125);
DISPLAY INVISIBLE (-5350 2125);
FORCEPROP 1 LAST COMMENT_BODY TRUE
J 0
(-5720 2155);
DISPLAY 0.872340 (-5720 2155);
PAINT GREEN (-5720 2155);
DISPLAY INVISIBLE (-5720 2155);
FORCEPROP 2 LAST PATH I78
J 0
(-5500 2325);
DISPLAY 0.680851 (-5500 2325);
DISPLAY INVISIBLE (-5500 2325);
FORCEADD OFFPAGE..1
(-8425 2650);
FORCEPROP 2 LAST $XR0 150 
J 0
(-8677 2650);
DISPLAY 0.638298 (-8677 2650);
PAINT MONO (-8677 2650);
FORCEPROP 2 LAST CDS_LIB standard
J 0
(-8425 2650);
DISPLAY INVISIBLE (-8425 2650);
FORCEPROP 1 LAST OFFPAGE TRUE
J 0
(-8100 2525);
DISPLAY 0.872340 (-8100 2525);
PAINT GREEN (-8100 2525);
DISPLAY INVISIBLE (-8100 2525);
FORCEPROP 1 LAST COMMENT_BODY TRUE
J 0
(-8300 2550);
DISPLAY 0.872340 (-8300 2550);
PAINT GREEN (-8300 2550);
DISPLAY INVISIBLE (-8300 2550);
FORCEPROP 2 LAST PATH I83
J 0
(-8375 2725);
DISPLAY 0.680851 (-8375 2725);
DISPLAY INVISIBLE (-8375 2725);
FORCEADD OFFPAGE..1
(-8425 2600);
FORCEPROP 2 LAST $XR0 150 
J 0
(-8677 2600);
DISPLAY 0.638298 (-8677 2600);
PAINT MONO (-8677 2600);
FORCEPROP 2 LAST CDS_LIB standard
J 0
(-8425 2600);
DISPLAY INVISIBLE (-8425 2600);
FORCEPROP 1 LAST OFFPAGE TRUE
J 0
(-8100 2475);
DISPLAY 0.872340 (-8100 2475);
PAINT GREEN (-8100 2475);
DISPLAY INVISIBLE (-8100 2475);
FORCEPROP 1 LAST COMMENT_BODY TRUE
J 0
(-8300 2500);
DISPLAY 0.872340 (-8300 2500);
PAINT GREEN (-8300 2500);
DISPLAY INVISIBLE (-8300 2500);
FORCEPROP 2 LAST PATH I84
J 0
(-8375 2675);
DISPLAY 0.680851 (-8375 2675);
DISPLAY INVISIBLE (-8375 2675);
FORCEADD Q_CAP_DIFFBUS..2
(-7300 2650);
FORCEPROP 1 LAST LOCATION C6019
J 0
(-7600 2650);
DISPLAY 0.723404 (-7600 2650);
PAINT GREEN (-7600 2650);
FORCEPROP 0 LAST $SEC 1
J 0
(-7325 2850);
DISPLAY 0.680851 (-7325 2850);
PAINT MONO (-7325 2850);
DISPLAY INVISIBLE (-7325 2850);
FORCEPROP 0 LAST CDS_SEC 1
J 0
(-7325 2850);
DISPLAY 0.680851 (-7325 2850);
DISPLAY INVISIBLE (-7325 2850);
FORCEPROP 0 LASTPIN (-7375 2650) $PN 1
J 2
(-7385 2660);
DISPLAY 0.680851 (-7385 2660);
PAINT MONO (-7385 2660);
FORCEPROP 0 LASTPIN (-7225 2650) $PN 2
J 0
(-7215 2660);
DISPLAY 0.680851 (-7215 2660);
PAINT MONO (-7215 2660);
FORCEPROP 1 LAST MATERIAL X6S
J 0
(-7325 2850);
DISPLAY 0.723404 (-7325 2850);
PAINT GREEN (-7325 2850);
FORCEPROP 2 LAST VOLTAGE 6.3V
J 0
(-7166 2846);
DISPLAY 0.680851 (-7166 2846);
FORCEPROP 2 LAST PACK_TYPE C0402
J 0
(-7316 2946);
DISPLAY 0.680851 (-7316 2946);
FORCEPROP 0 LAST ROOM USB3_HUB1
J 0
(-7425 2725);
DISPLAY 0.680851 (-7425 2725);
FORCEPROP 2 LAST TOLERANCE 10%
J 0
(-6991 2846);
DISPLAY 0.680851 (-6991 2846);
FORCEPROP 2 LAST VALUE DIFF BUS_0.33UF
J 0
(-7150 2650);
DISPLAY 0.680851 (-7150 2650);
FORCEPROP 1 LAST PIN_NAMES_ROTATE True
J 0
(-7300 2650);
DISPLAY 0.489362 (-7300 2650);
PAINT GREEN (-7300 2650);
DISPLAY INVISIBLE (-7300 2650);
FORCEPROP 1 LAST CDS_LMAN_SYM_OUTLINE -25,50,25,-50
J 0
(-7300 2650);
DISPLAY 0.468085 (-7300 2650);
PAINT GREEN (-7300 2650);
DISPLAY INVISIBLE (-7300 2650);
FORCEPROP 2 LAST CDS_LIB pure_quanta
J 0
(-7300 2650);
DISPLAY INVISIBLE (-7300 2650);
FORCEPROP 1 LAST PATH I85
J 0
(-7300 2650);
DISPLAY 0.723404 (-7300 2650);
DISPLAY INVISIBLE (-7300 2650);
FORCEPROP 1 LAST PART_NUMBER SP_CH4331KEB01
J 0
(-7325 2909);
DISPLAY 0.723404 (-7325 2909);
PAINT GREEN (-7325 2909);
DISPLAY INVISIBLE (-7325 2909);
FORCEADD Q_CAP_DIFFBUS..2
(-7300 2600);
FORCEPROP 1 LAST LOCATION C6020
J 0
(-7600 2600);
DISPLAY 0.723404 (-7600 2600);
PAINT GREEN (-7600 2600);
FORCEPROP 0 LAST $SEC 1
J 0
(-7200 2650);
DISPLAY 0.680851 (-7200 2650);
PAINT MONO (-7200 2650);
DISPLAY INVISIBLE (-7200 2650);
FORCEPROP 0 LAST CDS_SEC 1
J 0
(-7200 2650);
DISPLAY 0.680851 (-7200 2650);
DISPLAY INVISIBLE (-7200 2650);
FORCEPROP 0 LASTPIN (-7375 2600) $PN 1
J 2
(-7385 2610);
DISPLAY 0.680851 (-7385 2610);
PAINT MONO (-7385 2610);
FORCEPROP 0 LASTPIN (-7225 2600) $PN 2
J 0
(-7215 2610);
DISPLAY 0.680851 (-7215 2610);
PAINT MONO (-7215 2610);
FORCEPROP 0 LAST ROOM USB3_HUB1
J 0
(-7425 2525);
DISPLAY 0.680851 (-7425 2525);
FORCEPROP 2 LAST VALUE DIFF BUS_0.33UF
J 0
(-7150 2600);
DISPLAY 0.680851 (-7150 2600);
FORCEPROP 0 LAST TOLERANCE 10%
J 0
(-7000 2650);
DISPLAY 0.680851 (-7000 2650);
DISPLAY INVISIBLE (-7000 2650);
FORCEPROP 0 LAST VOLTAGE 6.3V
J 0
(-7175 2650);
DISPLAY 0.680851 (-7175 2650);
DISPLAY INVISIBLE (-7175 2650);
FORCEPROP 1 LAST MATERIAL X6S
J 0
(-7334 2654);
DISPLAY 0.723404 (-7334 2654);
PAINT GREEN (-7334 2654);
DISPLAY INVISIBLE (-7334 2654);
FORCEPROP 0 LAST PACK_TYPE C0402
J 0
(-7325 2750);
DISPLAY 0.680851 (-7325 2750);
DISPLAY INVISIBLE (-7325 2750);
FORCEPROP 1 LAST PIN_NAMES_ROTATE True
J 0
(-7300 2600);
DISPLAY 0.489362 (-7300 2600);
PAINT GREEN (-7300 2600);
DISPLAY INVISIBLE (-7300 2600);
FORCEPROP 2 LAST CDS_LIB pure_quanta
J 0
(-7300 2600);
DISPLAY INVISIBLE (-7300 2600);
FORCEPROP 1 LAST CDS_LMAN_SYM_OUTLINE -25,50,25,-50
J 0
(-7300 2600);
DISPLAY 0.468085 (-7300 2600);
PAINT GREEN (-7300 2600);
DISPLAY INVISIBLE (-7300 2600);
FORCEPROP 1 LAST PATH I86
J 0
(-7300 2600);
DISPLAY 0.723404 (-7300 2600);
DISPLAY INVISIBLE (-7300 2600);
FORCEPROP 1 LAST PART_NUMBER SP_CH4331KEB01
J 0
(-7334 2713);
DISPLAY 0.723404 (-7334 2713);
PAINT GREEN (-7334 2713);
DISPLAY INVISIBLE (-7334 2713);
FORCEADD Q_CAP_DIFFBUS..2
(-7300 2300);
FORCEPROP 1 LAST LOCATION C6021
J 0
(-7600 2300);
DISPLAY 0.723404 (-7600 2300);
PAINT GREEN (-7600 2300);
FORCEPROP 0 LAST $SEC 1
J 0
(-7200 2350);
DISPLAY 0.680851 (-7200 2350);
PAINT MONO (-7200 2350);
DISPLAY INVISIBLE (-7200 2350);
FORCEPROP 0 LAST CDS_SEC 1
J 0
(-7200 2350);
DISPLAY 0.680851 (-7200 2350);
DISPLAY INVISIBLE (-7200 2350);
FORCEPROP 0 LASTPIN (-7375 2300) $PN 1
J 2
(-7385 2310);
DISPLAY 0.680851 (-7385 2310);
PAINT MONO (-7385 2310);
FORCEPROP 0 LASTPIN (-7225 2300) $PN 2
J 0
(-7215 2310);
DISPLAY 0.680851 (-7215 2310);
PAINT MONO (-7215 2310);
FORCEPROP 0 LAST ROOM USB3_HUB2
J 0
(-7450 2350);
DISPLAY 0.680851 (-7450 2350);
FORCEPROP 2 LAST VALUE DIFF BUS_0.33UF
J 0
(-7150 2300);
DISPLAY 0.680851 (-7150 2300);
FORCEPROP 1 LAST PIN_NAMES_ROTATE True
J 0
(-7300 2300);
DISPLAY 0.489362 (-7300 2300);
PAINT GREEN (-7300 2300);
DISPLAY INVISIBLE (-7300 2300);
FORCEPROP 0 LAST PACK_TYPE C0402
J 0
(-7325 2450);
DISPLAY 0.680851 (-7325 2450);
DISPLAY INVISIBLE (-7325 2450);
FORCEPROP 1 LAST MATERIAL X6S
J 0
(-7334 2354);
DISPLAY 0.723404 (-7334 2354);
PAINT GREEN (-7334 2354);
DISPLAY INVISIBLE (-7334 2354);
FORCEPROP 0 LAST VOLTAGE 6.3V
J 0
(-7175 2350);
DISPLAY 0.680851 (-7175 2350);
DISPLAY INVISIBLE (-7175 2350);
FORCEPROP 0 LAST TOLERANCE 10%
J 0
(-7000 2350);
DISPLAY 0.680851 (-7000 2350);
DISPLAY INVISIBLE (-7000 2350);
FORCEPROP 1 LAST CDS_LMAN_SYM_OUTLINE -25,50,25,-50
J 0
(-7300 2300);
DISPLAY 0.468085 (-7300 2300);
PAINT GREEN (-7300 2300);
DISPLAY INVISIBLE (-7300 2300);
FORCEPROP 2 LAST CDS_LIB pure_quanta
J 0
(-7300 2300);
DISPLAY INVISIBLE (-7300 2300);
FORCEPROP 1 LAST PATH I87
J 0
(-7300 2300);
DISPLAY 0.723404 (-7300 2300);
DISPLAY INVISIBLE (-7300 2300);
FORCEPROP 1 LAST PART_NUMBER SP_CH4331KEB01
J 0
(-7334 2413);
DISPLAY 0.723404 (-7334 2413);
PAINT GREEN (-7334 2413);
DISPLAY INVISIBLE (-7334 2413);
FORCEADD Q_CAP_DIFFBUS..2
(-7300 2250);
FORCEPROP 1 LAST LOCATION C6022
J 0
(-7600 2250);
DISPLAY 0.723404 (-7600 2250);
PAINT GREEN (-7600 2250);
FORCEPROP 0 LAST $SEC 1
J 0
(-7200 2300);
DISPLAY 0.680851 (-7200 2300);
PAINT MONO (-7200 2300);
DISPLAY INVISIBLE (-7200 2300);
FORCEPROP 0 LAST CDS_SEC 1
J 0
(-7200 2300);
DISPLAY 0.680851 (-7200 2300);
DISPLAY INVISIBLE (-7200 2300);
FORCEPROP 0 LASTPIN (-7375 2250) $PN 1
J 2
(-7385 2260);
DISPLAY 0.680851 (-7385 2260);
PAINT MONO (-7385 2260);
FORCEPROP 0 LASTPIN (-7225 2250) $PN 2
J 0
(-7215 2260);
DISPLAY 0.680851 (-7215 2260);
PAINT MONO (-7215 2260);
FORCEPROP 0 LAST ROOM USB3_HUB2
J 0
(-7425 2175);
DISPLAY 0.680851 (-7425 2175);
FORCEPROP 2 LAST VALUE DIFF BUS_0.33UF
J 0
(-7150 2250);
DISPLAY 0.680851 (-7150 2250);
FORCEPROP 0 LAST TOLERANCE 10%
J 0
(-7000 2300);
DISPLAY 0.680851 (-7000 2300);
DISPLAY INVISIBLE (-7000 2300);
FORCEPROP 0 LAST VOLTAGE 6.3V
J 0
(-7175 2300);
DISPLAY 0.680851 (-7175 2300);
DISPLAY INVISIBLE (-7175 2300);
FORCEPROP 1 LAST MATERIAL X6S
J 0
(-7334 2304);
DISPLAY 0.723404 (-7334 2304);
PAINT GREEN (-7334 2304);
DISPLAY INVISIBLE (-7334 2304);
FORCEPROP 0 LAST PACK_TYPE C0402
J 0
(-7325 2400);
DISPLAY 0.680851 (-7325 2400);
DISPLAY INVISIBLE (-7325 2400);
FORCEPROP 1 LAST PIN_NAMES_ROTATE True
J 0
(-7300 2250);
DISPLAY 0.489362 (-7300 2250);
PAINT GREEN (-7300 2250);
DISPLAY INVISIBLE (-7300 2250);
FORCEPROP 1 LAST CDS_LMAN_SYM_OUTLINE -25,50,25,-50
J 0
(-7300 2250);
DISPLAY 0.468085 (-7300 2250);
PAINT GREEN (-7300 2250);
DISPLAY INVISIBLE (-7300 2250);
FORCEPROP 2 LAST CDS_LIB pure_quanta
J 0
(-7300 2250);
DISPLAY INVISIBLE (-7300 2250);
FORCEPROP 1 LAST PATH I88
J 0
(-7300 2250);
DISPLAY 0.723404 (-7300 2250);
DISPLAY INVISIBLE (-7300 2250);
FORCEPROP 1 LAST PART_NUMBER SP_CH4331KEB01
J 0
(-7334 2363);
DISPLAY 0.723404 (-7334 2363);
PAINT GREEN (-7334 2363);
DISPLAY INVISIBLE (-7334 2363);
FORCEADD OFFPAGE..2
(-1425 4550);
FORCEPROP 2 LAST $XR0 150 
J 0
(-1236 4550);
DISPLAY 0.638298 (-1236 4550);
PAINT MONO (-1236 4550);
FORCEPROP 2 LAST CDS_LIB standard
J 0
(-1425 4550);
DISPLAY INVISIBLE (-1425 4550);
FORCEPROP 1 LAST OFFPAGE TRUE
J 0
(-1100 4425);
DISPLAY 0.872340 (-1100 4425);
PAINT GREEN (-1100 4425);
DISPLAY INVISIBLE (-1100 4425);
FORCEPROP 1 LAST COMMENT_BODY TRUE
J 0
(-1470 4455);
DISPLAY 0.872340 (-1470 4455);
PAINT GREEN (-1470 4455);
DISPLAY INVISIBLE (-1470 4455);
FORCEPROP 2 LAST PATH I89
J 0
(-1250 4625);
DISPLAY 0.680851 (-1250 4625);
DISPLAY INVISIBLE (-1250 4625);
FORCEADD OFFPAGE..2
(-1425 4500);
FORCEPROP 2 LAST $XR0 150 
J 0
(-1236 4500);
DISPLAY 0.638298 (-1236 4500);
PAINT MONO (-1236 4500);
FORCEPROP 2 LAST CDS_LIB standard
J 0
(-1425 4500);
DISPLAY INVISIBLE (-1425 4500);
FORCEPROP 1 LAST OFFPAGE TRUE
J 0
(-1100 4375);
DISPLAY 0.872340 (-1100 4375);
PAINT GREEN (-1100 4375);
DISPLAY INVISIBLE (-1100 4375);
FORCEPROP 1 LAST COMMENT_BODY TRUE
J 0
(-1470 4405);
DISPLAY 0.872340 (-1470 4405);
PAINT GREEN (-1470 4405);
DISPLAY INVISIBLE (-1470 4405);
FORCEPROP 2 LAST PATH I90
J 0
(-1250 4575);
DISPLAY 0.680851 (-1250 4575);
DISPLAY INVISIBLE (-1250 4575);
FORCEADD OFFPAGE..1
(-4375 4500);
FORCEPROP 2 LAST $XR0 176 
J 0
(-4627 4500);
DISPLAY 0.638298 (-4627 4500);
PAINT MONO (-4627 4500);
FORCEPROP 2 LAST CDS_LIB standard
J 0
(-4375 4500);
DISPLAY INVISIBLE (-4375 4500);
FORCEPROP 1 LAST OFFPAGE TRUE
J 0
(-4050 4375);
DISPLAY 0.872340 (-4050 4375);
PAINT GREEN (-4050 4375);
DISPLAY INVISIBLE (-4050 4375);
FORCEPROP 1 LAST COMMENT_BODY TRUE
J 0
(-4250 4400);
DISPLAY 0.872340 (-4250 4400);
PAINT GREEN (-4250 4400);
DISPLAY INVISIBLE (-4250 4400);
FORCEPROP 2 LAST PATH I95
J 0
(-4325 4575);
DISPLAY 0.680851 (-4325 4575);
DISPLAY INVISIBLE (-4325 4575);
FORCEADD OFFPAGE..1
(-4375 4550);
FORCEPROP 2 LAST $XR0 176 
J 0
(-4627 4550);
DISPLAY 0.638298 (-4627 4550);
PAINT MONO (-4627 4550);
FORCEPROP 2 LAST CDS_LIB standard
J 0
(-4375 4550);
DISPLAY INVISIBLE (-4375 4550);
FORCEPROP 1 LAST OFFPAGE TRUE
J 0
(-4050 4425);
DISPLAY 0.872340 (-4050 4425);
PAINT GREEN (-4050 4425);
DISPLAY INVISIBLE (-4050 4425);
FORCEPROP 1 LAST COMMENT_BODY TRUE
J 0
(-4250 4450);
DISPLAY 0.872340 (-4250 4450);
PAINT GREEN (-4250 4450);
DISPLAY INVISIBLE (-4250 4450);
FORCEPROP 2 LAST PATH I96
J 0
(-4325 4625);
DISPLAY 0.680851 (-4325 4625);
DISPLAY INVISIBLE (-4325 4625);
FORCEADD OFFPAGE..1
(-4350 3925);
FORCEPROP 2 LAST $XR0 178 
J 0
(-4632 3925);
DISPLAY 0.638298 (-4632 3925);
PAINT MONO (-4632 3925);
FORCEPROP 2 LAST CDS_LIB standard
J 0
(-4350 3925);
DISPLAY INVISIBLE (-4350 3925);
FORCEPROP 1 LAST OFFPAGE TRUE
J 0
(-4025 3800);
DISPLAY 0.872340 (-4025 3800);
PAINT GREEN (-4025 3800);
DISPLAY INVISIBLE (-4025 3800);
FORCEPROP 1 LAST COMMENT_BODY TRUE
J 0
(-4225 3825);
DISPLAY 0.872340 (-4225 3825);
PAINT GREEN (-4225 3825);
DISPLAY INVISIBLE (-4225 3825);
FORCEPROP 2 LAST PATH I97
J 0
(-4300 4000);
DISPLAY 0.680851 (-4300 4000);
DISPLAY INVISIBLE (-4300 4000);
FORCEADD OFFPAGE..1
(-4350 3975);
FORCEPROP 2 LAST $XR0 178 
J 0
(-4632 3975);
DISPLAY 0.638298 (-4632 3975);
PAINT MONO (-4632 3975);
FORCEPROP 2 LAST CDS_LIB standard
J 0
(-4350 3975);
DISPLAY INVISIBLE (-4350 3975);
FORCEPROP 1 LAST OFFPAGE TRUE
J 0
(-4025 3850);
DISPLAY 0.872340 (-4025 3850);
PAINT GREEN (-4025 3850);
DISPLAY INVISIBLE (-4025 3850);
FORCEPROP 1 LAST COMMENT_BODY TRUE
J 0
(-4225 3875);
DISPLAY 0.872340 (-4225 3875);
PAINT GREEN (-4225 3875);
DISPLAY INVISIBLE (-4225 3875);
FORCEPROP 2 LAST PATH I98
J 0
(-4300 4050);
DISPLAY 0.680851 (-4300 4050);
DISPLAY INVISIBLE (-4300 4050);
FORCEADD CAD_NOTE..1
(-3250 3300);
FORCEPROP 0 LAST S1 C6015/C6017 C6016/C6018 CO-LAYOUT
J 0
(-3375 3175);
DISPLAY 0.808511 (-3375 3175);
PAINT WHITE (-3375 3175);
FORCEPROP 2 LAST CDS_LIB pure_quanta_power
J 0
(-3250 3300);
DISPLAY INVISIBLE (-3250 3300);
FORCEPROP 1 LAST COMMENT_BODY TRUE
J 0
(-3225 3400);
DISPLAY 0.978723 (-3225 3400);
DISPLAY INVISIBLE (-3225 3400);
FORCEADD CAD_NOTE..1
(-3075 6575);
FORCEPROP 0 LAST S1 R6194/R6196 R6195/R6197 CO-LAYOUT
J 0
(-3200 6450);
DISPLAY 0.808511 (-3200 6450);
PAINT WHITE (-3200 6450);
FORCEPROP 2 LAST CDS_LIB pure_quanta_power
J 0
(-3075 6575);
DISPLAY INVISIBLE (-3075 6575);
FORCEPROP 1 LAST COMMENT_BODY TRUE
J 0
(-3050 6675);
DISPLAY 0.978723 (-3050 6675);
DISPLAY INVISIBLE (-3050 6675);
FORCEADD CAD_NOTE..1
(-7700 3300);
FORCEPROP 0 LAST S1 C6019/C6021 C6020/C6022 CO-LAYOUT
J 0
(-7825 3175);
DISPLAY 0.808511 (-7825 3175);
PAINT WHITE (-7825 3175);
FORCEPROP 2 LAST CDS_LIB pure_quanta_power
J 0
(-7700 3300);
DISPLAY INVISIBLE (-7700 3300);
FORCEPROP 1 LAST COMMENT_BODY TRUE
J 0
(-7675 3400);
DISPLAY 0.978723 (-7675 3400);
DISPLAY INVISIBLE (-7675 3400);
FORCEADD DNS..1
(-6175 4025);
PAINT RED (-6175 4025);
FORCEPROP 2 LAST CDS_LIB mstr_misc
J 0
(-6175 4025);
DISPLAY INVISIBLE (-6175 4025);
FORCEPROP 2 LAST BOM_COST VR_SYSTEM 
J 0
(-6350 4200);
DISPLAY 0.680851 (-6350 4200);
DISPLAY INVISIBLE (-6350 4200);
FORCEPROP 1 LAST COMMENT_BODY TRUE
J 0
(-6175 4025);
DISPLAY INVISIBLE (-6175 4025);
FORCEADD DNS..1
(-8625 5650);
PAINT RED (-8625 5650);
FORCEPROP 2 LAST CDS_LIB mstr_misc
J 0
(-8625 5650);
DISPLAY INVISIBLE (-8625 5650);
FORCEPROP 2 LAST BOM_COST VR_SYSTEM 
J 0
(-8800 5825);
DISPLAY 0.680851 (-8800 5825);
DISPLAY INVISIBLE (-8800 5825);
FORCEPROP 1 LAST COMMENT_BODY TRUE
J 0
(-8625 5650);
DISPLAY INVISIBLE (-8625 5650);
FORCEADD DNS..1
(-6050 5400);
PAINT RED (-6050 5400);
FORCEPROP 2 LAST CDS_LIB mstr_misc
J 0
(-6050 5400);
DISPLAY INVISIBLE (-6050 5400);
FORCEPROP 2 LAST BOM_COST VR_SYSTEM 
J 0
(-6225 5575);
DISPLAY 0.680851 (-6225 5575);
DISPLAY INVISIBLE (-6225 5575);
FORCEPROP 1 LAST COMMENT_BODY TRUE
J 0
(-6050 5400);
DISPLAY INVISIBLE (-6050 5400);
FORCEADD DNS..1
(-6025 4025);
PAINT RED (-6025 4025);
FORCEPROP 2 LAST BOM_COST VR_SYSTEM 
J 0
(-6200 4200);
DISPLAY 0.680851 (-6200 4200);
DISPLAY INVISIBLE (-6200 4200);
FORCEPROP 2 LAST CDS_LIB mstr_misc
J 0
(-6025 4025);
DISPLAY INVISIBLE (-6025 4025);
FORCEPROP 1 LAST COMMENT_BODY TRUE
J 0
(-6025 4025);
DISPLAY INVISIBLE (-6025 4025);
FORCEADD DNS..1
(-8775 5650);
PAINT RED (-8775 5650);
FORCEPROP 2 LAST CDS_LIB mstr_misc
J 0
(-8775 5650);
DISPLAY INVISIBLE (-8775 5650);
FORCEPROP 2 LAST BOM_COST VR_SYSTEM 
J 0
(-8950 5825);
DISPLAY 0.680851 (-8950 5825);
DISPLAY INVISIBLE (-8950 5825);
FORCEPROP 1 LAST COMMENT_BODY TRUE
J 0
(-8775 5650);
DISPLAY INVISIBLE (-8775 5650);
FORCEADD QUANTA_TITLE_BLOCK_C..1
(200 50);
FORCEPROP 0 LAST CDS_CON_LAST_MODIFIED Thu Sep 14 16:12:47 2023
J 0
(-1685 65);
DISPLAY INVISIBLE (-1685 65);
FORCEPROP 1 LAST CUSTOM_TXT_CDS <CON_LAST_MODIFIED>
J 0
(-1685 65);
DISPLAY 0.978723 (-1685 65);
FORCEPROP 2 LAST CUSTOM_TXT_CDS <XR_PAGE_TITLE>
J 0
(-7690 5300);
DISPLAY 0.638298 (-7690 5300);
PAINT PINK (-7690 5300);
DISPLAY INVISIBLE (-7690 5300);
FORCEPROP 1 LAST CUSTOM_TXT_CDS <NAME_2>
J 0
(-2975 100);
FORCEPROP 1 LAST CUSTOM_TXT_CDS <NAME_1>
J 0
(-2975 225);
FORCEPROP 1 LAST CUSTOM_TXT_CDS <Q_NUMBER>
J 0
(-1203 153);
DISPLAY 1.212766 (-1203 153);
FORCEPROP 1 LAST CUSTOM_TXT_CDS <Q_PROJ>
J 0
(-2182 152);
DISPLAY 1.212766 (-2182 152);
FORCEPROP 1 LAST CUSTOM_TXT_CDS <Q_REV>
J 0
(16 153);
DISPLAY 1.212766 (16 153);
FORCEPROP 1 LAST CUSTOM_TXT_CDS <CON_PAGE_NUM> OF <CON_TOTAL_PAGES>
J 0
(-246 68);
DISPLAY 0.978723 (-246 68);
FORCEPROP 1 LAST Q_TITLE USB3.0 EXT HUB USB SIGNAL SELECT
J 0
(-9075 125);
DISPLAY 2.446809 (-9075 125);
PAINT GREEN (-9075 125);
FORCEPROP 2 LAST CDS_LIB pure_quanta
J 0
(200 50);
DISPLAY INVISIBLE (200 50);
FORCEPROP 1 LAST CDS_LMAN_SYM_OUTLINE -9475,6775,100,-125
J 0
(200 50);
DISPLAY 0.468085 (200 50);
PAINT GREEN (200 50);
DISPLAY INVISIBLE (200 50);
FORCEPROP 2 LAST PAGE_BORDER TRUE
J 0
(-7690 5300);
DISPLAY 0.638298 (-7690 5300);
PAINT PINK (-7690 5300);
DISPLAY INVISIBLE (-7690 5300);
FORCEPROP 2 LAST CDS_XR_PAGE_TITLE CR-180 : @T6G_MB_LIB.T6G(SCH_1):PAGE180
J 0
(-7690 5300);
DISPLAY 0.638298 (-7690 5300);
PAINT PINK (-7690 5300);
DISPLAY INVISIBLE (-7690 5300);
FORCEPROP 1 LAST Q_DEPT BU9
J 1
(-3563 99);
DISPLAY 1.957447 (-3563 99);
PAINT GREEN (-3563 99);
DISPLAY INVISIBLE (-3563 99);
FORCEPROP 1 LAST COMMENT_BODY TRUE
J 0
(212 37);
DISPLAY 0.978723 (212 37);
PAINT GREEN (212 37);
DISPLAY INVISIBLE (212 37);
FORCEADD DNS..1
(-8500 4400);
PAINT RED (-8500 4400);
FORCEPROP 2 LAST CDS_LIB mstr_misc
J 0
(-8500 4400);
DISPLAY INVISIBLE (-8500 4400);
FORCEPROP 2 LAST BOM_COST VR_SYSTEM 
J 0
(-8675 4575);
DISPLAY 0.680851 (-8675 4575);
DISPLAY INVISIBLE (-8675 4575);
FORCEPROP 1 LAST COMMENT_BODY TRUE
J 0
(-8500 4400);
DISPLAY INVISIBLE (-8500 4400);
FORCEADD DNS..1
(-6200 5400);
PAINT RED (-6200 5400);
FORCEPROP 2 LAST CDS_LIB mstr_misc
J 0
(-6200 5400);
DISPLAY INVISIBLE (-6200 5400);
FORCEPROP 2 LAST BOM_COST VR_SYSTEM 
J 0
(-6375 5575);
DISPLAY 0.680851 (-6375 5575);
DISPLAY INVISIBLE (-6375 5575);
FORCEPROP 1 LAST COMMENT_BODY TRUE
J 0
(-6200 5400);
DISPLAY INVISIBLE (-6200 5400);
FORCEADD DNS..1
(-8675 4425);
PAINT RED (-8675 4425);
FORCEPROP 2 LAST BOM_COST VR_SYSTEM 
J 0
(-8850 4600);
DISPLAY 0.680851 (-8850 4600);
DISPLAY INVISIBLE (-8850 4600);
FORCEPROP 2 LAST CDS_LIB mstr_misc
J 0
(-8675 4425);
DISPLAY INVISIBLE (-8675 4425);
FORCEPROP 1 LAST COMMENT_BODY TRUE
J 0
(-8675 4425);
DISPLAY INVISIBLE (-8675 4425);
FORCEADD CAD_NOTE..1
(-8325 5250);
FORCEPROP 0 LAST S1 C6003/C6013/R341 C6004/C6014/R342 CO-LAYOUT
J 0
(-8450 5125);
DISPLAY 0.808511 (-8450 5125);
PAINT WHITE (-8450 5125);
FORCEPROP 2 LAST CDS_LIB pure_quanta_power
J 0
(-8325 5250);
DISPLAY INVISIBLE (-8325 5250);
FORCEPROP 1 LAST COMMENT_BODY TRUE
J 0
(-8300 5350);
DISPLAY 0.978723 (-8300 5350);
DISPLAY INVISIBLE (-8300 5350);
FORCEADD CAD_NOTE..1
(-8575 6575);
FORCEPROP 0 LAST S1 R6190/R6192/R339 R6191/R6193/R340 CO-LAYOUT
J 0
(-8700 6450);
DISPLAY 0.808511 (-8700 6450);
PAINT WHITE (-8700 6450);
FORCEPROP 2 LAST CDS_LIB pure_quanta_power
J 0
(-8575 6575);
DISPLAY INVISIBLE (-8575 6575);
FORCEPROP 1 LAST COMMENT_BODY TRUE
J 0
(-8550 6675);
DISPLAY 0.978723 (-8550 6675);
DISPLAY INVISIBLE (-8550 6675);
FORCEADD CAD_NOTE..1
(-3300 5000);
FORCEPROP 0 LAST S1 C6023/C6025 C6024/C6026 CO-LAYOUT
J 0
(-3425 4875);
DISPLAY 0.808511 (-3425 4875);
PAINT WHITE (-3425 4875);
FORCEPROP 2 LAST CDS_LIB pure_quanta_power
J 0
(-3300 5000);
DISPLAY INVISIBLE (-3300 5000);
FORCEPROP 1 LAST COMMENT_BODY TRUE
J 0
(-3275 5100);
DISPLAY 0.978723 (-3275 5100);
DISPLAY INVISIBLE (-3275 5100);
WIRE 16 -1 (-8750 5550)(-8750 5350);
WIRE 16 -1 (-8675 5550)(-8675 5350);
WIRE 16 -1 (-8575 4325)(-8575 4100);
WIRE 16 -1 (-8650 4300)(-8650 4100);
WIRE 16 -1 (-6075 5300)(-6075 5100);
WIRE 16 -1 (-6150 5300)(-6150 5100);
WIRE 16 -1 (-6150 3950)(-6150 3750);
WIRE 16 -1 (-6075 3950)(-6075 3750);
WIRE 16 -1 (-6025 4450)(-6150 4450);
WIRE 16 -1 (-6150 4150)(-6150 4450);
WIRE 16 -1 (-6150 4450)(-7475 4450);
FORCEPROP 2 LAST SIG_NAME USB3_CPU0_BMC_TX_C2_DP
J 0
(-6860 4460);
DISPLAY 0.680851 (-6860 4460);
WIRE 16 -1 (-7475 4400)(-6075 4400);
FORCEPROP 2 LAST SIG_NAME USB3_CPU0_BMC_TX_C2_DN
J 0
(-6860 4410);
DISPLAY 0.680851 (-6860 4410);
WIRE 16 -1 (-6075 4400)(-6025 4400);
WIRE 16 -1 (-6075 4150)(-6075 4400);
WIRE 16 -1 (-5925 5650)(-6150 5650);
WIRE 16 -1 (-6150 5500)(-6150 5650);
WIRE 16 -1 (-6150 5650)(-7425 5650);
FORCEPROP 2 LAST SIG_NAME USB2_CPU0_P0_R2_DP
J 0
(-6810 5660);
DISPLAY 0.680851 (-6810 5660);
WIRE 16 -1 (-5925 5600)(-6075 5600);
WIRE 16 -1 (-6075 5500)(-6075 5600);
WIRE 16 -1 (-6075 5600)(-7425 5600);
FORCEPROP 2 LAST SIG_NAME USB2_CPU0_P0_R2_DN
J 0
(-6810 5610);
DISPLAY 0.680851 (-6810 5610);
WIRE 16 -1 (-8075 5600)(-7625 5600);
WIRE 16 -1 (-8075 5950)(-8075 5600);
WIRE 16 -1 (-7650 5950)(-8075 5950);
WIRE 16 -1 (-8075 5950)(-8675 5950);
FORCEPROP 2 LAST SIG_NAME USB2_CPU0_P0_DN
J 0
(-8485 5960);
DISPLAY 0.680851 (-8485 5960);
WIRE 16 -1 (-8675 5750)(-8675 5950);
WIRE 16 -1 (-8675 5950)(-8775 5950);
WIRE 16 -1 (-7875 5650)(-7625 5650);
WIRE 16 -1 (-7875 6000)(-7875 5650);
WIRE 16 -1 (-7875 6000)(-7650 6000);
WIRE 16 -1 (-8750 6000)(-7875 6000);
FORCEPROP 2 LAST SIG_NAME USB2_CPU0_P0_DP
J 0
(-8510 6010);
DISPLAY 0.680851 (-8510 6010);
WIRE 16 -1 (-8775 6000)(-8750 6000);
WIRE 16 -1 (-8750 5750)(-8750 6000);
WIRE 16 2175 (-3450 4825)(-2575 4825);
WIRE 16 2175 (-3450 4825)(-3450 3750);
WIRE 16 2175 (-2575 4825)(-2575 3750);
WIRE 16 2175 (-3450 3750)(-2575 3750);
WIRE 16 -1 (-2375 4550)(-1475 4550);
FORCEPROP 2 LAST SIG_NAME USB3_CPU0_BMC_TX_BUF_C_DP
J 0
(-2285 4560);
DISPLAY 0.680851 (-2285 4560);
WIRE 16 -1 (-2375 4550)(-3050 4550);
WIRE 16 -1 (-2375 3975)(-2375 4550);
WIRE 16 -1 (-3025 3975)(-2375 3975);
WIRE 16 -1 (-3050 4500)(-2175 4500);
WIRE 16 -1 (-2175 4500)(-1475 4500);
WIRE 16 -1 (-2175 3925)(-2175 4500);
FORCEPROP 2 LAST SIG_NAME USB3_CPU0_BMC_TX_BUF_C_DN
J 0
(-2310 4510);
DISPLAY 0.680851 (-2310 4510);
WIRE 16 -1 (-3025 3925)(-2175 3925);
WIRE 16 2175 (-3300 6150)(-2200 6150);
WIRE 16 2175 (-3300 6150)(-3300 5300);
WIRE 16 2175 (-2200 6150)(-2200 5300);
WIRE 16 2175 (-3300 5300)(-2200 5300);
WIRE 16 -1 (-5750 2600)(-7225 2600);
FORCEPROP 2 LAST SIG_NAME USB3_CPU0_BMC_RX_C1_DN
J 0
(-6510 2610);
DISPLAY 0.680851 (-6510 2610);
WIRE 16 -1 (-7225 2250)(-5725 2250);
FORCEPROP 2 LAST SIG_NAME USB3_CPU0_BMC_RX_C2_DN
J 0
(-6510 2260);
DISPLAY 0.680851 (-6510 2260);
WIRE 16 -1 (-5750 2650)(-7225 2650);
FORCEPROP 2 LAST SIG_NAME USB3_CPU0_BMC_RX_C1_DP
J 0
(-6510 2660);
DISPLAY 0.680851 (-6510 2660);
WIRE 16 -1 (-5725 2300)(-7225 2300);
FORCEPROP 2 LAST SIG_NAME USB3_CPU0_BMC_RX_C2_DP
J 0
(-6510 2310);
DISPLAY 0.680851 (-6510 2310);
WIRE 16 2175 (-7650 2825)(-6675 2825);
WIRE 16 2175 (-7650 2825)(-7650 2125);
WIRE 16 2175 (-6675 2825)(-6675 2125);
WIRE 16 2175 (-7650 2125)(-6675 2125);
WIRE 16 2175 (-7850 4950)(-6975 4950);
WIRE 16 2175 (-7850 4950)(-7850 4250);
WIRE 16 2175 (-6975 4950)(-6975 4250);
WIRE 16 2175 (-7850 4250)(-6975 4250);
WIRE 16 -1 (-8575 4525)(-8575 4750);
WIRE 16 -1 (-8175 4750)(-8575 4750);
FORCEPROP 2 LAST SIG_NAME USB3_CPU0_BMC_TX_DN
J 0
(-8485 4760);
DISPLAY 0.680851 (-8485 4760);
WIRE 16 -1 (-8675 4750)(-8575 4750);
WIRE 16 -1 (-7675 4750)(-8175 4750);
WIRE 16 -1 (-8175 4400)(-8175 4750);
WIRE 16 -1 (-7675 4400)(-8175 4400);
WIRE 16 -1 (-8650 4500)(-8650 4800);
WIRE 16 -1 (-8650 4800)(-7975 4800);
FORCEPROP 2 LAST SIG_NAME USB3_CPU0_BMC_TX_DP
J 0
(-8485 4810);
DISPLAY 0.680851 (-8485 4810);
WIRE 16 -1 (-8675 4800)(-8650 4800);
WIRE 16 -1 (-7975 4800)(-7675 4800);
WIRE 16 -1 (-7975 4800)(-7975 4450);
WIRE 16 -1 (-7975 4450)(-7675 4450);
WIRE 16 -1 (-6050 4750)(-7475 4750);
FORCEPROP 2 LAST SIG_NAME USB3_CPU0_BMC_TX_C1_DN
J 0
(-6835 4760);
DISPLAY 0.680851 (-6835 4760);
WIRE 16 -1 (-7475 4800)(-6050 4800);
FORCEPROP 2 LAST SIG_NAME USB3_CPU0_BMC_TX_C1_DP
J 0
(-6860 4810);
DISPLAY 0.680851 (-6860 4810);
WIRE 16 2175 (-7825 5475)(-6850 5475);
WIRE 16 2175 (-7825 6125)(-7825 5475);
WIRE 16 2175 (-6850 6125)(-6850 5475);
WIRE 16 2175 (-7825 6125)(-6850 6125);
WIRE 16 -1 (-5950 5950)(-7450 5950);
FORCEPROP 2 LAST SIG_NAME USB2_CPU0_P0_R1_DN
J 0
(-6685 5960);
DISPLAY 0.680851 (-6685 5960);
WIRE 16 -1 (-5950 6000)(-7450 6000);
FORCEPROP 2 LAST SIG_NAME USB2_CPU0_P0_R1_DP
J 0
(-6685 6010);
DISPLAY 0.680851 (-6685 6010);
WIRE 16 -1 (-4275 2725)(-3250 2725);
FORCEPROP 2 LAST SIG_NAME USB3_CPU0_BMC_RX_HUB1_DP
J 0
(-4260 2735);
DISPLAY 0.680851 (-4260 2735);
WIRE 16 -1 (-3025 2150)(-2325 2150);
WIRE 16 -1 (-2325 2150)(-2325 2725);
WIRE 16 -1 (-2325 2725)(-1425 2725);
FORCEPROP 2 LAST SIG_NAME USB3_CPU0_BMC_RX_HUB_C_DP
J 0
(-2260 2735);
DISPLAY 0.680851 (-2260 2735);
WIRE 16 -1 (-3100 2725)(-2325 2725);
WIRE 16 -1 (-3025 2100)(-2125 2100);
WIRE 16 -1 (-2125 2100)(-2125 2675);
WIRE 16 -1 (-2125 2675)(-1425 2675);
WIRE 16 -1 (-3100 2675)(-2125 2675);
FORCEPROP 2 LAST SIG_NAME USB3_CPU0_BMC_RX_HUB_C_DN
J 0
(-2260 2685);
DISPLAY 0.680851 (-2260 2685);
WIRE 16 2175 (-3475 2900)(-2450 2900);
WIRE 16 2175 (-3475 2900)(-3475 1950);
WIRE 16 2175 (-2450 2900)(-2450 1950);
WIRE 16 2175 (-3475 1950)(-2450 1950);
WIRE 16 -1 (-4250 2150)(-3225 2150);
FORCEPROP 2 LAST SIG_NAME USB3_CPU0_BMC_RX_HUB2_DP
J 0
(-4235 2160);
DISPLAY 0.680851 (-4235 2160);
WIRE 16 -1 (-4250 2100)(-3225 2100);
FORCEPROP 2 LAST SIG_NAME USB3_CPU0_BMC_RX_HUB2_DN
J 0
(-4235 2110);
DISPLAY 0.680851 (-4235 2110);
WIRE 16 -1 (-4275 2675)(-3250 2675);
FORCEPROP 2 LAST SIG_NAME USB3_CPU0_BMC_RX_HUB1_DN
J 0
(-4260 2685);
DISPLAY 0.680851 (-4260 2685);
WIRE 16 -1 (-4300 3975)(-3225 3975);
FORCEPROP 2 LAST SIG_NAME USB3_CPU0_BMC_HUB2_TX_DP
J 0
(-4260 3985);
DISPLAY 0.680851 (-4260 3985);
WIRE 16 -1 (-4300 3925)(-3225 3925);
FORCEPROP 2 LAST SIG_NAME USB3_CPU0_BMC_HUB2_TX_DN
J 0
(-4260 3935);
DISPLAY 0.680851 (-4260 3935);
WIRE 16 -1 (-4325 4500)(-3250 4500);
FORCEPROP 2 LAST SIG_NAME USB3_CPU0_BMC_HUB1_TX_DN
J 0
(-4310 4510);
DISPLAY 0.680851 (-4310 4510);
WIRE 16 -1 (-4325 4550)(-3250 4550);
FORCEPROP 2 LAST SIG_NAME USB3_CPU0_BMC_HUB1_TX_DP
J 0
(-4285 4560);
DISPLAY 0.680851 (-4285 4560);
WIRE 16 -1 (-2875 5950)(-1950 5950);
WIRE 16 -1 (-1950 5950)(-1250 5950);
WIRE 16 -1 (-1950 5375)(-1950 5950);
FORCEPROP 2 LAST SIG_NAME USB2_HUB_EXT_DN
J 0
(-2060 5960);
DISPLAY 0.680851 (-2060 5960);
WIRE 16 -1 (-1950 5375)(-2850 5375);
WIRE 16 -1 (-2875 6000)(-2150 6000);
WIRE 16 -1 (-2150 6000)(-1250 6000);
FORCEPROP 2 LAST SIG_NAME USB2_HUB_EXT_DP
J 0
(-2060 6010);
DISPLAY 0.680851 (-2060 6010);
WIRE 16 -1 (-2150 5425)(-2150 6000);
WIRE 16 -1 (-2150 5425)(-2850 5425);
WIRE 16 -1 (-4075 5375)(-3050 5375);
FORCEPROP 2 LAST SIG_NAME USB2_CPU0_P0_HUB2_R_DN
J 0
(-4035 5385);
DISPLAY 0.680851 (-4035 5385);
WIRE 16 -1 (-4075 5425)(-3050 5425);
FORCEPROP 2 LAST SIG_NAME USB2_CPU0_P0_HUB2_R_DP
J 0
(-4035 5435);
DISPLAY 0.680851 (-4035 5435);
WIRE 16 -1 (-4100 5950)(-3075 5950);
FORCEPROP 2 LAST SIG_NAME USB2_CPU0_P0_HUB1_R_DN
J 0
(-4035 5960);
DISPLAY 0.680851 (-4035 5960);
WIRE 16 -1 (-4100 6000)(-3075 6000);
FORCEPROP 2 LAST SIG_NAME USB2_CPU0_P0_HUB1_R_DP
J 0
(-4035 6010);
DISPLAY 0.680851 (-4035 6010);
WIRE 16 -1 (-7375 2250)(-7875 2250);
WIRE 16 -1 (-7875 2600)(-7875 2250);
WIRE 16 -1 (-7375 2600)(-7875 2600);
WIRE 16 -1 (-7875 2600)(-8375 2600);
FORCEPROP 2 LAST SIG_NAME USB3_CPU0_BMC_RX_DN
J 0
(-8285 2610);
DISPLAY 0.680851 (-8285 2610);
WIRE 16 -1 (-7675 2650)(-7375 2650);
WIRE 16 -1 (-7675 2650)(-7675 2300);
WIRE 16 -1 (-8375 2650)(-7675 2650);
FORCEPROP 2 LAST SIG_NAME USB3_CPU0_BMC_RX_DP
J 0
(-8310 2660);
DISPLAY 0.680851 (-8310 2660);
WIRE 16 -1 (-7675 2300)(-7375 2300);
DOT 1 (-8575 4750);
DOT 1 (-8650 4800);
DOT 1 (-6075 4400);
DOT 1 (-6150 4450);
DOT 1 (-6075 5600);
DOT 1 (-8675 5950);
DOT 1 (-8750 6000);
DOT 1 (-2375 4550);
DOT 1 (-7875 2600);
DOT 1 (-2125 2675);
DOT 1 (-2325 2725);
DOT 1 (-1950 5950);
DOT 1 (-7675 2650);
DOT 1 (-7975 4800);
DOT 1 (-7875 6000);
DOT 1 (-8075 5950);
DOT 1 (-8175 4750);
DOT 1 (-6150 5650);
DOT 1 (-2150 6000);
DOT 1 (-2175 4500);
FORCENOTE
FROM 1ST HUB
(-5150 4625) 0;
DISPLAY LEFT (-5150 4625);
DISPLAY 1.021277 (-5150 4625);
FORCENOTE
TO 1ST HUB
(-6575 4900) 0;
DISPLAY LEFT (-6575 4900);
DISPLAY 1.021277 (-6575 4900);
FORCENOTE
FROM 1ST HUB
(-5100 2800) 0;
DISPLAY LEFT (-5100 2800);
DISPLAY 1.021277 (-5100 2800);
FORCENOTE
TO 2ND HUB
(-6550 4525) 0;
DISPLAY LEFT (-6550 4525);
DISPLAY 1.021277 (-6550 4525);
FORCENOTE
FROM 2ND HUB
(-5125 4025) 0;
DISPLAY LEFT (-5125 4025);
DISPLAY 1.021277 (-5125 4025);
FORCENOTE
FROM 1ST HUB
(-4925 6075) 0;
DISPLAY LEFT (-4925 6075);
DISPLAY 1.021277 (-4925 6075);
FORCENOTE
FROM SCM
(-8750 2725) 0;
DISPLAY LEFT (-8750 2725);
DISPLAY 1.021277 (-8750 2725);
FORCENOTE
FROM 2ND HUB
(-4900 5475) 0;
DISPLAY LEFT (-4900 5475);
DISPLAY 1.021277 (-4900 5475);
FORCENOTE
FROM CPU
(-9025 6075) 0;
DISPLAY LEFT (-9025 6075);
DISPLAY 1.021277 (-9025 6075);
FORCENOTE
TO SCM
(-1500 4675) 0;
DISPLAY LEFT (-1500 4675);
DISPLAY 1.021277 (-1500 4675);
FORCENOTE
TO CPU
(-1450 2850) 0;
DISPLAY LEFT (-1450 2850);
DISPLAY 1.021277 (-1450 2850);
FORCENOTE
TO SCM
(-1275 6125) 0;
DISPLAY LEFT (-1275 6125);
DISPLAY 1.021277 (-1275 6125);
FORCENOTE
TO 1ST HUB
(-6475 6100) 0;
DISPLAY LEFT (-6475 6100);
DISPLAY 1.021277 (-6475 6100);
FORCENOTE
TO 2ND HUB
(-6450 5725) 0;
DISPLAY LEFT (-6450 5725);
DISPLAY 1.021277 (-6450 5725);
FORCENOTE
FROM CPU
(-9050 4875) 0;
DISPLAY LEFT (-9050 4875);
DISPLAY 1.021277 (-9050 4875);
FORCENOTE
TO 1ST HUB
(-6275 2750) 0;
DISPLAY LEFT (-6275 2750);
DISPLAY 1.021277 (-6275 2750);
FORCENOTE
FROM 2ND HUB
(-5075 2200) 0;
DISPLAY LEFT (-5075 2200);
DISPLAY 1.021277 (-5075 2200);
FORCENOTE
TO 2ND HUB
(-6250 2375) 0;
DISPLAY LEFT (-6250 2375);
DISPLAY 1.021277 (-6250 2375);
QUIT
